FILE_TYPE = MACRO_DRAWING;
SET COLOR_WIRE YELLOW;
SET COLOR_PROP MONO;
SET COLOR_DOT WHITE;
SET COLOR_ARC YELLOW;
SET COLOR_BODY GREEN;
SET COLOR_NOTE MONO;
SET PROP_DISPLAY VALUE;
SET PAGE_NUMBER P198;
FORCEADD SLG55021..1
(-7000 3825);
FORCEPROP 2 LASTPIN (-7300 3975) $PN 1
J 2
(-7310 3985);
DISPLAY 0.617021 (-7310 3985);
PAINT MONO (-7310 3985);
FORCEPROP 2 LASTPIN (-7300 3775) $PN 3
J 2
(-7310 3785);
DISPLAY 0.617021 (-7310 3785);
PAINT MONO (-7310 3785);
FORCEPROP 2 LASTPIN (-7300 3875) $PN 2
J 2
(-7310 3885);
DISPLAY 0.617021 (-7310 3885);
PAINT MONO (-7310 3885);
FORCEPROP 1 LAST PART_NUMBER G56246-001
J 0
(-7250 3525);
DISPLAY 0.617021 (-7250 3525);
PAINT BLUE (-7250 3525);
FORCEPROP 2 LASTPIN (-6700 3775) $PN 6
J 0
(-6690 3785);
DISPLAY 0.617021 (-6690 3785);
PAINT MONO (-6690 3785);
FORCEPROP 2 LASTPIN (-6700 3625) $PN 9
J 0
(-6690 3635);
DISPLAY 0.617021 (-6690 3635);
PAINT MONO (-6690 3635);
FORCEPROP 2 LASTPIN (-6700 3675) $PN 4
J 0
(-6690 3685);
DISPLAY 0.617021 (-6690 3685);
PAINT MONO (-6690 3685);
FORCEPROP 2 LASTPIN (-6700 3825) $PN 7
J 0
(-6690 3835);
DISPLAY 0.617021 (-6690 3835);
PAINT MONO (-6690 3835);
FORCEPROP 2 LASTPIN (-6700 3975) $PN 8
J 0
(-6690 3985);
DISPLAY 0.617021 (-6690 3985);
PAINT MONO (-6690 3985);
FORCEPROP 2 LASTPIN (-6700 3875) $PN 5
J 0
(-6690 3885);
DISPLAY 0.617021 (-6690 3885);
PAINT MONO (-6690 3885);
FORCEPROP 1 LAST MATERIAL IC
J 0
(-7250 4125);
DISPLAY 0.617021 (-7250 4125);
PAINT SKYBLUE (-7250 4125);
FORCEPROP 1 LAST LOCATION EU2T1
J 0
(-7250 4175);
DISPLAY 0.617021 (-7250 4175);
PAINT AQUA (-7250 4175);
FORCEPROP 1 LAST CDS_LMAN_SYM_OUTLINE -250,250,250,-250
J 0
(-7000 3825);
DISPLAY 0.468085 (-7000 3825);
PAINT GREEN (-7000 3825);
DISPLAY INVISIBLE (-7000 3825);
FORCEPROP 2 LAST CDS_LIB mstr_vreg
J 0
(-7000 3825);
PAINT ORANGE (-7000 3825);
DISPLAY INVISIBLE (-7000 3825);
FORCEPROP 0 LAST ROOM P3V3_PWR_SWITCH
J 0
(-7250 4275);
DISPLAY 1.021277 (-7250 4275);
PAINT ORANGE (-7250 4275);
DISPLAY INVISIBLE (-7250 4275);
FORCEPROP 2 LAST CDS_LOCATION EU2T1
J 0
(-7250 4175);
DISPLAY 0.617021 (-7250 4175);
PAINT AQUA (-7250 4175);
DISPLAY INVISIBLE (-7250 4175);
FORCEPROP 2 LAST $SEC 1
J 0
(-7250 4225);
PAINT MONO (-7250 4225);
DISPLAY INVISIBLE (-7250 4225);
FORCEPROP 2 LAST CDS_SEC 1
J 0
(-7250 4225);
PAINT MONO (-7250 4225);
DISPLAY INVISIBLE (-7250 4225);
FORCEPROP 1 LAST PACK_TYPE SM
J 0
(-7250 4225);
PAINT SKYBLUE (-7250 4225);
DISPLAY INVISIBLE (-7250 4225);
FORCEPROP 1 LAST PATH I1
J 0
(-7000 4125);
PAINT GREEN (-7000 4125);
DISPLAY INVISIBLE (-7000 4125);
FORCEADD GND..1
(-2775 3425);
FORCEPROP 3 LASTPIN (-2775 3475) SIG_NAME GND\g
J 0
(-2765 3485);
DISPLAY 0.659574 (-2765 3485);
PAINT MONO (-2765 3485);
DISPLAY INVISIBLE (-2765 3485);
FORCEPROP 1 LAST PATH I12
J 0
(-2700 3425);
DISPLAY 0.872340 (-2700 3425);
PAINT AQUA (-2700 3425);
DISPLAY INVISIBLE (-2700 3425);
FORCEPROP 1 LAST BODY_TYPE PLUMBING
J 0
(-2820 3382);
DISPLAY 0.340426 (-2820 3382);
PAINT GREEN (-2820 3382);
DISPLAY INVISIBLE (-2820 3382);
FORCEPROP 1 LAST SIZE 1B
J 0
(-2700 3375);
DISPLAY 1.170213 (-2700 3375);
PAINT AQUA (-2700 3375);
DISPLAY INVISIBLE (-2700 3375);
FORCEPROP 2 LAST CDS_LIB mstr_symbols
J 0
(-2775 3425);
PAINT ORANGE (-2775 3425);
DISPLAY INVISIBLE (-2775 3425);
FORCEPROP 1 LAST VOLTAGE 0.0V
J 0
(-2820 3382);
DISPLAY 0.340426 (-2820 3382);
PAINT SKYBLUE (-2820 3382);
DISPLAY INVISIBLE (-2820 3382);
FORCEPROP 1 LAST HDL_POWER GND
J 0
(-2775 3575);
DISPLAY 1.170213 (-2775 3575);
PAINT GREEN (-2775 3575);
DISPLAY INVISIBLE (-2775 3575);
FORCEADD SLG55021..1
(-3300 3800);
FORCEPROP 2 LASTPIN (-3600 3750) $PN 3
J 2
(-3610 3760);
DISPLAY 0.617021 (-3610 3760);
PAINT ORANGE (-3610 3760);
FORCEPROP 2 LASTPIN (-3600 3950) $PN 1
J 2
(-3610 3960);
DISPLAY 0.617021 (-3610 3960);
PAINT ORANGE (-3610 3960);
FORCEPROP 2 LASTPIN (-3600 3850) $PN 2
J 2
(-3610 3860);
DISPLAY 0.617021 (-3610 3860);
PAINT ORANGE (-3610 3860);
FORCEPROP 1 LAST PART_NUMBER G56246-001
J 0
(-3550 3500);
DISPLAY 0.617021 (-3550 3500);
PAINT BLUE (-3550 3500);
FORCEPROP 2 LASTPIN (-3000 3650) $PN 4
J 0
(-2990 3660);
DISPLAY 0.617021 (-2990 3660);
PAINT ORANGE (-2990 3660);
FORCEPROP 2 LASTPIN (-3000 3750) $PN 6
J 0
(-2990 3760);
DISPLAY 0.617021 (-2990 3760);
PAINT ORANGE (-2990 3760);
FORCEPROP 2 LASTPIN (-3000 3800) $PN 7
J 0
(-2990 3810);
DISPLAY 0.617021 (-2990 3810);
PAINT ORANGE (-2990 3810);
FORCEPROP 2 LASTPIN (-3000 3600) $PN 9
J 0
(-2990 3610);
DISPLAY 0.617021 (-2990 3610);
PAINT ORANGE (-2990 3610);
FORCEPROP 2 LASTPIN (-3000 3850) $PN 5
J 0
(-2990 3860);
DISPLAY 0.617021 (-2990 3860);
PAINT ORANGE (-2990 3860);
FORCEPROP 1 LAST MATERIAL IC
J 0
(-3550 4100);
DISPLAY 0.617021 (-3550 4100);
PAINT SKYBLUE (-3550 4100);
FORCEPROP 1 LAST LOCATION EU8B1
J 0
(-3550 4150);
DISPLAY 0.617021 (-3550 4150);
PAINT AQUA (-3550 4150);
FORCEPROP 2 LASTPIN (-3000 3950) $PN 8
J 0
(-2990 3960);
DISPLAY 0.617021 (-2990 3960);
PAINT ORANGE (-2990 3960);
FORCEPROP 2 LAST CDS_LIB mstr_vreg
J 0
(-3300 3800);
PAINT ORANGE (-3300 3800);
DISPLAY INVISIBLE (-3300 3800);
FORCEPROP 1 LAST CDS_LMAN_SYM_OUTLINE -250,250,250,-250
J 0
(-3300 3800);
DISPLAY 0.468085 (-3300 3800);
PAINT GREEN (-3300 3800);
DISPLAY INVISIBLE (-3300 3800);
FORCEPROP 0 LAST ROOM P5V_PWR_SWITCH
J 0
(-3550 4250);
DISPLAY 1.021277 (-3550 4250);
PAINT ORANGE (-3550 4250);
DISPLAY INVISIBLE (-3550 4250);
FORCEPROP 1 LAST PACK_TYPE SM
J 0
(-3550 4200);
PAINT SKYBLUE (-3550 4200);
DISPLAY INVISIBLE (-3550 4200);
FORCEPROP 1 LAST PATH I13
J 0
(-3300 4100);
PAINT GREEN (-3300 4100);
DISPLAY INVISIBLE (-3300 4100);
FORCEPROP 2 LAST CDS_LOCATION EU8B1
J 0
(-3550 4150);
DISPLAY 0.617021 (-3550 4150);
PAINT AQUA (-3550 4150);
DISPLAY INVISIBLE (-3550 4150);
FORCEPROP 2 LAST SEC 1
J 0
(-3550 4200);
DISPLAY 0.680851 (-3550 4200);
PAINT MONO (-3550 4200);
DISPLAY INVISIBLE (-3550 4200);
FORCEPROP 2 LAST SEC_TYPE SM
J 0
(-3550 4200);
DISPLAY 1.021277 (-3550 4200);
PAINT ORANGE (-3550 4200);
DISPLAY INVISIBLE (-3550 4200);
FORCEADD P5V_STBY..1
(-7375 2525);
FORCEPROP 3 LASTPIN (-7375 2475) SIG_NAME P5V_STBY\g
J 0
(-7365 2485);
DISPLAY 0.659574 (-7365 2485);
PAINT MONO (-7365 2485);
DISPLAY INVISIBLE (-7365 2485);
FORCEPROP 1 LAST HDL_POWER P5V_STBY
J 0
(-7675 2400);
DISPLAY 0.872340 (-7675 2400);
PAINT ORANGE (-7675 2400);
DISPLAY INVISIBLE (-7675 2400);
FORCEPROP 1 LAST VOLTAGE 5.0V
J 0
(-7420 2482);
DISPLAY 0.340426 (-7420 2482);
PAINT SKYBLUE (-7420 2482);
DISPLAY INVISIBLE (-7420 2482);
FORCEPROP 1 LAST BODY_TYPE PLUMBING
J 0
(-7420 2482);
DISPLAY 0.340426 (-7420 2482);
PAINT GREEN (-7420 2482);
DISPLAY INVISIBLE (-7420 2482);
FORCEPROP 1 LAST PATH I15
J 0
(-7330 2527);
DISPLAY 0.340426 (-7330 2527);
PAINT GREEN (-7330 2527);
DISPLAY INVISIBLE (-7330 2527);
FORCEPROP 1 LAST SIZE 1B
J 0
(-7330 2547);
DISPLAY 0.340426 (-7330 2547);
PAINT GREEN (-7330 2547);
DISPLAY INVISIBLE (-7330 2547);
FORCEPROP 2 LAST CDS_LIB mstr_symbols
J 0
(-7375 2525);
PAINT ORANGE (-7375 2525);
DISPLAY INVISIBLE (-7375 2525);
FORCEADD GND..1
(-6200 1475);
FORCEPROP 3 LASTPIN (-6200 1525) SIG_NAME GND\g
J 0
(-6190 1535);
DISPLAY 0.659574 (-6190 1535);
PAINT MONO (-6190 1535);
DISPLAY INVISIBLE (-6190 1535);
FORCEPROP 1 LAST BODY_TYPE PLUMBING
J 0
(-6245 1432);
DISPLAY 0.340426 (-6245 1432);
PAINT GREEN (-6245 1432);
DISPLAY INVISIBLE (-6245 1432);
FORCEPROP 2 LAST CDS_LIB mstr_symbols
J 0
(-6200 1475);
PAINT ORANGE (-6200 1475);
DISPLAY INVISIBLE (-6200 1475);
FORCEPROP 1 LAST VOLTAGE 0.0V
J 0
(-6245 1432);
DISPLAY 0.340426 (-6245 1432);
PAINT SKYBLUE (-6245 1432);
DISPLAY INVISIBLE (-6245 1432);
FORCEPROP 1 LAST HDL_POWER GND
J 0
(-6200 1625);
DISPLAY 1.170213 (-6200 1625);
PAINT GREEN (-6200 1625);
DISPLAY INVISIBLE (-6200 1625);
FORCEPROP 1 LAST PATH I18
J 0
(-6125 1475);
DISPLAY 0.872340 (-6125 1475);
PAINT AQUA (-6125 1475);
DISPLAY INVISIBLE (-6125 1475);
FORCEPROP 1 LAST SIZE 1B
J 0
(-6125 1425);
DISPLAY 1.170213 (-6125 1425);
PAINT AQUA (-6125 1425);
DISPLAY INVISIBLE (-6125 1425);
FORCEADD SLG55021..1
(-6725 1850);
FORCEPROP 2 LASTPIN (-7025 1800) $PN 3
J 2
(-7035 1810);
DISPLAY 0.617021 (-7035 1810);
PAINT ORANGE (-7035 1810);
FORCEPROP 2 LASTPIN (-7025 2000) $PN 1
J 2
(-7035 2010);
DISPLAY 0.617021 (-7035 2010);
PAINT ORANGE (-7035 2010);
FORCEPROP 2 LASTPIN (-6425 1900) $PN 5
J 0
(-6415 1910);
DISPLAY 0.617021 (-6415 1910);
PAINT ORANGE (-6415 1910);
FORCEPROP 2 LASTPIN (-6425 1850) $PN 7
J 0
(-6415 1860);
DISPLAY 0.617021 (-6415 1860);
PAINT ORANGE (-6415 1860);
FORCEPROP 2 LASTPIN (-6425 1700) $PN 4
J 0
(-6415 1710);
DISPLAY 0.617021 (-6415 1710);
PAINT ORANGE (-6415 1710);
FORCEPROP 2 LASTPIN (-6425 2000) $PN 8
J 0
(-6415 2010);
DISPLAY 0.617021 (-6415 2010);
PAINT ORANGE (-6415 2010);
FORCEPROP 2 LASTPIN (-6425 1800) $PN 6
J 0
(-6415 1810);
DISPLAY 0.617021 (-6415 1810);
PAINT ORANGE (-6415 1810);
FORCEPROP 2 LASTPIN (-6425 1650) $PN 9
J 0
(-6415 1660);
DISPLAY 0.617021 (-6415 1660);
PAINT ORANGE (-6415 1660);
FORCEPROP 1 LAST MATERIAL IC
J 0
(-6975 2150);
DISPLAY 0.617021 (-6975 2150);
PAINT SKYBLUE (-6975 2150);
FORCEPROP 1 LAST LOCATION EU7E1
J 0
(-6975 2200);
DISPLAY 0.617021 (-6975 2200);
PAINT AQUA (-6975 2200);
FORCEPROP 1 LAST PART_NUMBER G56246-001
J 0
(-6975 1550);
DISPLAY 0.617021 (-6975 1550);
PAINT BLUE (-6975 1550);
FORCEPROP 2 LASTPIN (-7025 1900) $PN 2
J 2
(-7035 1910);
DISPLAY 0.617021 (-7035 1910);
PAINT ORANGE (-7035 1910);
FORCEPROP 1 LAST CDS_LMAN_SYM_OUTLINE -250,250,250,-250
J 0
(-6725 1850);
DISPLAY 0.468085 (-6725 1850);
PAINT GREEN (-6725 1850);
DISPLAY INVISIBLE (-6725 1850);
FORCEPROP 2 LAST CDS_LIB mstr_vreg
J 0
(-6725 1850);
PAINT ORANGE (-6725 1850);
DISPLAY INVISIBLE (-6725 1850);
FORCEPROP 0 LAST ROOM P12V_PWR_SWITCH
J 0
(-6975 2300);
DISPLAY 1.021277 (-6975 2300);
PAINT ORANGE (-6975 2300);
DISPLAY INVISIBLE (-6975 2300);
FORCEPROP 2 LAST CDS_LOCATION EU7E1
J 0
(-6975 2200);
DISPLAY 0.617021 (-6975 2200);
PAINT AQUA (-6975 2200);
DISPLAY INVISIBLE (-6975 2200);
FORCEPROP 2 LAST SEC 1
J 0
(-6975 2250);
DISPLAY 0.680851 (-6975 2250);
PAINT MONO (-6975 2250);
DISPLAY INVISIBLE (-6975 2250);
FORCEPROP 2 LAST SEC_TYPE SM
J 0
(-6975 2250);
DISPLAY 1.021277 (-6975 2250);
PAINT ORANGE (-6975 2250);
DISPLAY INVISIBLE (-6975 2250);
FORCEPROP 1 LAST PACK_TYPE SM
J 0
(-6975 2250);
PAINT SKYBLUE (-6975 2250);
DISPLAY INVISIBLE (-6975 2250);
FORCEPROP 1 LAST PATH I19
J 0
(-6725 2150);
PAINT GREEN (-6725 2150);
DISPLAY INVISIBLE (-6725 2150);
FORCEADD P5V_STBY..1
(-7650 4525);
FORCEPROP 3 LASTPIN (-7650 4475) SIG_NAME P5V_STBY\g
J 0
(-7640 4485);
DISPLAY 0.659574 (-7640 4485);
PAINT MONO (-7640 4485);
DISPLAY INVISIBLE (-7640 4485);
FORCEPROP 1 LAST HDL_POWER P5V_STBY
J 0
(-7950 4400);
DISPLAY 0.872340 (-7950 4400);
PAINT ORANGE (-7950 4400);
DISPLAY INVISIBLE (-7950 4400);
FORCEPROP 1 LAST BODY_TYPE PLUMBING
J 0
(-7695 4482);
DISPLAY 0.340426 (-7695 4482);
PAINT GREEN (-7695 4482);
DISPLAY INVISIBLE (-7695 4482);
FORCEPROP 1 LAST VOLTAGE 5.0V
J 0
(-7695 4482);
DISPLAY 0.340426 (-7695 4482);
PAINT SKYBLUE (-7695 4482);
DISPLAY INVISIBLE (-7695 4482);
FORCEPROP 1 LAST SIZE 1B
J 0
(-7605 4547);
DISPLAY 0.340426 (-7605 4547);
PAINT GREEN (-7605 4547);
DISPLAY INVISIBLE (-7605 4547);
FORCEPROP 2 LAST CDS_LIB mstr_symbols
J 0
(-7650 4525);
PAINT ORANGE (-7650 4525);
DISPLAY INVISIBLE (-7650 4525);
FORCEPROP 1 LAST PATH I2
J 0
(-7605 4527);
DISPLAY 0.340426 (-7605 4527);
PAINT GREEN (-7605 4527);
DISPLAY INVISIBLE (-7605 4527);
FORCEADD P5V_STBY..1
(-1600 4725);
FORCEPROP 3 LASTPIN (-1600 4675) SIG_NAME P5V_STBY\g
J 0
(-1590 4685);
DISPLAY 0.659574 (-1590 4685);
PAINT MONO (-1590 4685);
DISPLAY INVISIBLE (-1590 4685);
FORCEPROP 1 LAST HDL_POWER P5V_STBY
J 0
(-1900 4600);
DISPLAY 0.872340 (-1900 4600);
PAINT ORANGE (-1900 4600);
DISPLAY INVISIBLE (-1900 4600);
FORCEPROP 1 LAST VOLTAGE 5.0V
J 0
(-1645 4682);
DISPLAY 0.340426 (-1645 4682);
PAINT SKYBLUE (-1645 4682);
DISPLAY INVISIBLE (-1645 4682);
FORCEPROP 1 LAST SIZE 1B
J 0
(-1555 4747);
DISPLAY 0.340426 (-1555 4747);
PAINT GREEN (-1555 4747);
DISPLAY INVISIBLE (-1555 4747);
FORCEPROP 2 LAST CDS_LIB mstr_symbols
J 0
(-1600 4725);
PAINT ORANGE (-1600 4725);
DISPLAY INVISIBLE (-1600 4725);
FORCEPROP 1 LAST BODY_TYPE PLUMBING
J 0
(-1645 4682);
DISPLAY 0.340426 (-1645 4682);
PAINT GREEN (-1645 4682);
DISPLAY INVISIBLE (-1645 4682);
FORCEPROP 1 LAST PATH I20
J 0
(-1555 4727);
DISPLAY 0.340426 (-1555 4727);
PAINT GREEN (-1555 4727);
DISPLAY INVISIBLE (-1555 4727);
FORCEADD P5V..1
(-1100 3600);
FORCEPROP 3 LASTPIN (-1100 3550) SIG_NAME P5V\g
J 0
(-1090 3560);
DISPLAY 0.659574 (-1090 3560);
PAINT MONO (-1090 3560);
DISPLAY INVISIBLE (-1090 3560);
FORCEPROP 1 LAST HDL_POWER P5V
J 0
(-1400 3475);
DISPLAY 0.872340 (-1400 3475);
PAINT ORANGE (-1400 3475);
DISPLAY INVISIBLE (-1400 3475);
FORCEPROP 1 LAST BODY_TYPE PLUMBING
J 0
(-1145 3557);
DISPLAY 0.340426 (-1145 3557);
PAINT GREEN (-1145 3557);
DISPLAY INVISIBLE (-1145 3557);
FORCEPROP 1 LAST PATH I21
J 0
(-1055 3602);
DISPLAY 0.340426 (-1055 3602);
PAINT GREEN (-1055 3602);
DISPLAY INVISIBLE (-1055 3602);
FORCEPROP 1 LAST SIZE 1B
J 0
(-1055 3622);
DISPLAY 0.340426 (-1055 3622);
PAINT GREEN (-1055 3622);
DISPLAY INVISIBLE (-1055 3622);
FORCEPROP 2 LAST CDS_LIB mstr_symbols
J 0
(-1100 3600);
PAINT ORANGE (-1100 3600);
DISPLAY INVISIBLE (-1100 3600);
FORCEPROP 1 LAST VOLTAGE +5.0V
J 0
(-1025 3750);
DISPLAY 1.021277 (-1025 3750);
PAINT SKYBLUE (-1025 3750);
DISPLAY INVISIBLE (-1025 3750);
FORCEADD P12V..1
(-4675 1625);
FORCEPROP 3 LASTPIN (-4675 1575) SIG_NAME P12V\g
J 0
(-4665 1585);
DISPLAY 0.659574 (-4665 1585);
PAINT MONO (-4665 1585);
DISPLAY INVISIBLE (-4665 1585);
FORCEPROP 1 LAST HDL_POWER P12V
J 0
(-4875 1475);
DISPLAY 0.872340 (-4875 1475);
PAINT ORANGE (-4875 1475);
DISPLAY INVISIBLE (-4875 1475);
FORCEPROP 1 LAST PATH I22
J 0
(-4630 1627);
DISPLAY 0.340426 (-4630 1627);
PAINT GREEN (-4630 1627);
DISPLAY INVISIBLE (-4630 1627);
FORCEPROP 1 LAST BODY_TYPE PLUMBING
J 0
(-4720 1582);
DISPLAY 0.340426 (-4720 1582);
PAINT GREEN (-4720 1582);
DISPLAY INVISIBLE (-4720 1582);
FORCEPROP 1 LAST SIZE 1B
J 0
(-4630 1647);
DISPLAY 0.340426 (-4630 1647);
PAINT GREEN (-4630 1647);
DISPLAY INVISIBLE (-4630 1647);
FORCEPROP 2 LAST CDS_LIB mstr_symbols
J 0
(-4675 1625);
PAINT ORANGE (-4675 1625);
DISPLAY INVISIBLE (-4675 1625);
FORCEPROP 1 LAST VOLTAGE +12.0V
J 0
(-4575 1775);
DISPLAY 1.021277 (-4575 1775);
PAINT SKYBLUE (-4575 1775);
DISPLAY INVISIBLE (-4575 1775);
FORCEADD P12V_STBY..1
(-5325 2575);
FORCEPROP 3 LASTPIN (-5325 2525) SIG_NAME P12V_STBY\g
J 0
(-5315 2535);
DISPLAY 0.659574 (-5315 2535);
PAINT MONO (-5315 2535);
DISPLAY INVISIBLE (-5315 2535);
FORCEPROP 1 LAST HDL_POWER P12V_STBY
J 0
(-5625 2450);
DISPLAY 0.872340 (-5625 2450);
PAINT ORANGE (-5625 2450);
DISPLAY INVISIBLE (-5625 2450);
FORCEPROP 1 LAST BODY_TYPE PLUMBING
J 0
(-5370 2532);
DISPLAY 0.340426 (-5370 2532);
PAINT GREEN (-5370 2532);
DISPLAY INVISIBLE (-5370 2532);
FORCEPROP 1 LAST VOLTAGE 12.0V
J 0
(-5370 2532);
DISPLAY 0.340426 (-5370 2532);
PAINT SKYBLUE (-5370 2532);
DISPLAY INVISIBLE (-5370 2532);
FORCEPROP 1 LAST PATH I23
J 0
(-5280 2577);
DISPLAY 0.340426 (-5280 2577);
PAINT GREEN (-5280 2577);
DISPLAY INVISIBLE (-5280 2577);
FORCEPROP 1 LAST SIZE 1B
J 0
(-5280 2597);
DISPLAY 0.340426 (-5280 2597);
PAINT GREEN (-5280 2597);
DISPLAY INVISIBLE (-5280 2597);
FORCEPROP 2 LAST CDS_LIB mstr_symbols
J 0
(-5325 2575);
PAINT ORANGE (-5325 2575);
DISPLAY INVISIBLE (-5325 2575);
FORCEADD CAP_A..1
(-8000 4200);
FORCEPROP 1 LAST PACK_TYPE 0402V
J 0
(-7950 4000);
DISPLAY 0.617021 (-7950 4000);
PAINT SKYBLUE (-7950 4000);
FORCEPROP 1 LAST PART_NUMBER A36096-030
J 0
(-7950 4050);
DISPLAY 0.617021 (-7950 4050);
PAINT BLUE (-7950 4050);
FORCEPROP 1 LASTPIN (-8000 4100) $PN 2
J 0
(-7990 4080);
DISPLAY 0.617021 (-7990 4080);
PAINT ORANGE (-7990 4080);
FORCEPROP 1 LASTPIN (-8000 4300) $PN 1
J 0
(-7990 4280);
DISPLAY 0.617021 (-7990 4280);
PAINT ORANGE (-7990 4280);
FORCEPROP 1 LAST MATERIAL X7R
J 0
(-7950 4100);
DISPLAY 0.617021 (-7950 4100);
PAINT SKYBLUE (-7950 4100);
FORCEPROP 1 LAST VOLTAGE 16V
J 0
(-7950 4200);
DISPLAY 0.617021 (-7950 4200);
PAINT SKYBLUE (-7950 4200);
FORCEPROP 1 LAST TOLERANCE 10%
J 0
(-7950 4150);
DISPLAY 0.617021 (-7950 4150);
PAINT SKYBLUE (-7950 4150);
FORCEPROP 1 LAST VALUE 0.1UF
J 0
(-7950 4250);
DISPLAY 0.617021 (-7950 4250);
PAINT SKYBLUE (-7950 4250);
FORCEPROP 1 LAST LOCATION C8F17
J 0
(-7950 4300);
DISPLAY 0.617021 (-7950 4300);
PAINT AQUA (-7950 4300);
FORCEPROP 2 LAST CDS_LIB dev_discrete
J 0
(-8000 4200);
PAINT ORANGE (-8000 4200);
DISPLAY INVISIBLE (-8000 4200);
FORCEPROP 2 LAST CDS_LOCATION C8F17
J 0
(-7950 4300);
DISPLAY 0.617021 (-7950 4300);
PAINT AQUA (-7950 4300);
DISPLAY INVISIBLE (-7950 4300);
FORCEPROP 1 LAST PATH I24
J 0
(-7950 4350);
DISPLAY 0.978723 (-7950 4350);
PAINT WHITE (-7950 4350);
DISPLAY INVISIBLE (-7950 4350);
FORCEPROP 2 LAST CDS_SEC 1
J 0
(-7950 4350);
PAINT ORANGE (-7950 4350);
DISPLAY INVISIBLE (-7950 4350);
FORCEPROP 0 LAST ROOM P3V3_PWR_SWITCH
J 0
(-7950 4400);
DISPLAY 1.021277 (-7950 4400);
PAINT ORANGE (-7950 4400);
DISPLAY INVISIBLE (-7950 4400);
FORCEPROP 2 LAST SEC_TYPE 0402V
J 0
(-7950 4400);
DISPLAY 1.021277 (-7950 4400);
PAINT ORANGE (-7950 4400);
DISPLAY INVISIBLE (-7950 4400);
FORCEPROP 2 LAST SEC 1
J 0
(-7950 4400);
DISPLAY 0.680851 (-7950 4400);
PAINT MONO (-7950 4400);
DISPLAY INVISIBLE (-7950 4400);
FORCEADD GND..1
(-8000 4000);
FORCEPROP 3 LASTPIN (-8000 4050) SIG_NAME GND\g
J 0
(-7990 4060);
DISPLAY 0.659574 (-7990 4060);
PAINT MONO (-7990 4060);
DISPLAY INVISIBLE (-7990 4060);
FORCEPROP 1 LAST BODY_TYPE PLUMBING
J 0
(-8045 3957);
DISPLAY 0.340426 (-8045 3957);
PAINT GREEN (-8045 3957);
DISPLAY INVISIBLE (-8045 3957);
FORCEPROP 2 LAST CDS_LIB mstr_symbols
J 0
(-8000 4000);
PAINT ORANGE (-8000 4000);
DISPLAY INVISIBLE (-8000 4000);
FORCEPROP 1 LAST VOLTAGE 0.0V
J 0
(-8045 3957);
DISPLAY 0.340426 (-8045 3957);
PAINT SKYBLUE (-8045 3957);
DISPLAY INVISIBLE (-8045 3957);
FORCEPROP 1 LAST PATH I25
J 0
(-7925 4000);
DISPLAY 0.872340 (-7925 4000);
PAINT AQUA (-7925 4000);
DISPLAY INVISIBLE (-7925 4000);
FORCEPROP 1 LAST SIZE 1B
J 0
(-7925 3950);
DISPLAY 1.170213 (-7925 3950);
PAINT AQUA (-7925 3950);
DISPLAY INVISIBLE (-7925 3950);
FORCEPROP 1 LAST HDL_POWER GND
J 0
(-8000 4150);
DISPLAY 1.170213 (-8000 4150);
PAINT GREEN (-8000 4150);
DISPLAY INVISIBLE (-8000 4150);
FORCEADD CAP_A..1
(-4300 4125);
FORCEPROP 1 LASTPIN (-4300 4025) $PN 2
J 0
(-4290 4005);
DISPLAY 0.617021 (-4290 4005);
PAINT ORANGE (-4290 4005);
FORCEPROP 1 LAST MATERIAL X7R
J 0
(-4250 4025);
DISPLAY 0.617021 (-4250 4025);
PAINT SKYBLUE (-4250 4025);
FORCEPROP 1 LASTPIN (-4300 4225) $PN 1
J 0
(-4290 4205);
DISPLAY 0.617021 (-4290 4205);
PAINT ORANGE (-4290 4205);
FORCEPROP 1 LAST PART_NUMBER A36096-030
J 0
(-4250 3975);
DISPLAY 0.617021 (-4250 3975);
PAINT BLUE (-4250 3975);
FORCEPROP 1 LAST TOLERANCE 10%
J 0
(-4250 4075);
DISPLAY 0.617021 (-4250 4075);
PAINT SKYBLUE (-4250 4075);
FORCEPROP 1 LAST VOLTAGE 16V
J 0
(-4250 4125);
DISPLAY 0.617021 (-4250 4125);
PAINT SKYBLUE (-4250 4125);
FORCEPROP 1 LAST VALUE 0.1UF
J 0
(-4250 4175);
DISPLAY 0.617021 (-4250 4175);
PAINT SKYBLUE (-4250 4175);
FORCEPROP 1 LAST PACK_TYPE 0402V
J 0
(-4250 3925);
DISPLAY 0.617021 (-4250 3925);
PAINT SKYBLUE (-4250 3925);
FORCEPROP 1 LAST LOCATION C8B8
J 0
(-4500 4125);
DISPLAY 0.617021 (-4500 4125);
PAINT AQUA (-4500 4125);
FORCEPROP 2 LAST CDS_LOCATION C8B8
J 0
(-4500 4125);
DISPLAY 0.617021 (-4500 4125);
PAINT AQUA (-4500 4125);
DISPLAY INVISIBLE (-4500 4125);
FORCEPROP 2 LAST CDS_LIB dev_discrete
J 0
(-4300 4125);
PAINT ORANGE (-4300 4125);
DISPLAY INVISIBLE (-4300 4125);
FORCEPROP 1 LAST PATH I26
J 0
(-4250 4275);
DISPLAY 0.978723 (-4250 4275);
PAINT WHITE (-4250 4275);
DISPLAY INVISIBLE (-4250 4275);
FORCEPROP 0 LAST ROOM P5V_PWR_SWITCH
J 0
(-4250 4275);
DISPLAY 1.021277 (-4250 4275);
PAINT ORANGE (-4250 4275);
DISPLAY INVISIBLE (-4250 4275);
FORCEPROP 2 LAST CDS_SEC 1
J 0
(-4250 4225);
PAINT ORANGE (-4250 4225);
DISPLAY INVISIBLE (-4250 4225);
FORCEPROP 2 LAST SEC_TYPE 0402V
J 0
(-4250 4325);
DISPLAY 1.021277 (-4250 4325);
PAINT ORANGE (-4250 4325);
DISPLAY INVISIBLE (-4250 4325);
FORCEPROP 2 LAST SEC 1
J 0
(-4250 4325);
DISPLAY 0.680851 (-4250 4325);
PAINT MONO (-4250 4325);
DISPLAY INVISIBLE (-4250 4325);
FORCEADD GND..1
(-4300 3950);
FORCEPROP 3 LASTPIN (-4300 4000) SIG_NAME GND\g
J 0
(-4290 4010);
DISPLAY 0.659574 (-4290 4010);
PAINT MONO (-4290 4010);
DISPLAY INVISIBLE (-4290 4010);
FORCEPROP 1 LAST VOLTAGE 0.0V
J 0
(-4345 3907);
DISPLAY 0.340426 (-4345 3907);
PAINT SKYBLUE (-4345 3907);
DISPLAY INVISIBLE (-4345 3907);
FORCEPROP 1 LAST SIZE 1B
J 0
(-4225 3900);
DISPLAY 1.170213 (-4225 3900);
PAINT AQUA (-4225 3900);
DISPLAY INVISIBLE (-4225 3900);
FORCEPROP 1 LAST BODY_TYPE PLUMBING
J 0
(-4345 3907);
DISPLAY 0.340426 (-4345 3907);
PAINT GREEN (-4345 3907);
DISPLAY INVISIBLE (-4345 3907);
FORCEPROP 2 LAST CDS_LIB mstr_symbols
J 0
(-4300 3950);
PAINT ORANGE (-4300 3950);
DISPLAY INVISIBLE (-4300 3950);
FORCEPROP 1 LAST PATH I27
J 0
(-4225 3950);
DISPLAY 0.872340 (-4225 3950);
PAINT AQUA (-4225 3950);
DISPLAY INVISIBLE (-4225 3950);
FORCEPROP 1 LAST HDL_POWER GND
J 0
(-4300 4100);
DISPLAY 1.170213 (-4300 4100);
PAINT GREEN (-4300 4100);
DISPLAY INVISIBLE (-4300 4100);
FORCEADD CAP_A..1
(-7725 2175);
FORCEPROP 1 LAST PACK_TYPE 0402V
J 0
(-7675 1975);
DISPLAY 0.617021 (-7675 1975);
PAINT SKYBLUE (-7675 1975);
FORCEPROP 1 LAST PART_NUMBER A36096-030
J 0
(-7675 2025);
DISPLAY 0.617021 (-7675 2025);
PAINT BLUE (-7675 2025);
FORCEPROP 1 LASTPIN (-7725 2075) $PN 2
J 0
(-7715 2055);
DISPLAY 0.617021 (-7715 2055);
PAINT ORANGE (-7715 2055);
FORCEPROP 1 LASTPIN (-7725 2275) $PN 1
J 0
(-7715 2255);
DISPLAY 0.617021 (-7715 2255);
PAINT ORANGE (-7715 2255);
FORCEPROP 1 LAST LOCATION C8E19
J 0
(-7675 2275);
DISPLAY 0.617021 (-7675 2275);
PAINT AQUA (-7675 2275);
FORCEPROP 1 LAST VALUE 0.1UF
J 0
(-7675 2225);
DISPLAY 0.617021 (-7675 2225);
PAINT SKYBLUE (-7675 2225);
FORCEPROP 1 LAST TOLERANCE 10%
J 0
(-7675 2125);
DISPLAY 0.617021 (-7675 2125);
PAINT SKYBLUE (-7675 2125);
FORCEPROP 1 LAST VOLTAGE 16V
J 0
(-7675 2175);
DISPLAY 0.617021 (-7675 2175);
PAINT SKYBLUE (-7675 2175);
FORCEPROP 1 LAST MATERIAL X7R
J 0
(-7675 2075);
DISPLAY 0.617021 (-7675 2075);
PAINT SKYBLUE (-7675 2075);
FORCEPROP 2 LAST CDS_LIB dev_discrete
J 0
(-7725 2175);
PAINT ORANGE (-7725 2175);
DISPLAY INVISIBLE (-7725 2175);
FORCEPROP 1 LAST PATH I28
J 0
(-7675 2325);
DISPLAY 0.978723 (-7675 2325);
PAINT WHITE (-7675 2325);
DISPLAY INVISIBLE (-7675 2325);
FORCEPROP 0 LAST ROOM P12V_PWR_SWITCH
J 0
(-7675 2375);
DISPLAY 1.021277 (-7675 2375);
PAINT ORANGE (-7675 2375);
DISPLAY INVISIBLE (-7675 2375);
FORCEPROP 2 LAST CDS_SEC 1
J 0
(-7675 2325);
PAINT ORANGE (-7675 2325);
DISPLAY INVISIBLE (-7675 2325);
FORCEPROP 2 LAST SEC_TYPE 0402V
J 0
(-7675 2375);
DISPLAY 1.021277 (-7675 2375);
PAINT ORANGE (-7675 2375);
DISPLAY INVISIBLE (-7675 2375);
FORCEPROP 2 LAST SEC 1
J 0
(-7675 2375);
DISPLAY 0.680851 (-7675 2375);
PAINT MONO (-7675 2375);
DISPLAY INVISIBLE (-7675 2375);
FORCEADD GND..1
(-7725 2000);
FORCEPROP 3 LASTPIN (-7725 2050) SIG_NAME GND\g
J 0
(-7715 2060);
DISPLAY 0.659574 (-7715 2060);
PAINT MONO (-7715 2060);
DISPLAY INVISIBLE (-7715 2060);
FORCEPROP 1 LAST BODY_TYPE PLUMBING
J 0
(-7770 1957);
DISPLAY 0.340426 (-7770 1957);
PAINT GREEN (-7770 1957);
DISPLAY INVISIBLE (-7770 1957);
FORCEPROP 2 LAST CDS_LIB mstr_symbols
J 0
(-7725 2000);
PAINT ORANGE (-7725 2000);
DISPLAY INVISIBLE (-7725 2000);
FORCEPROP 1 LAST VOLTAGE 0.0V
J 0
(-7770 1957);
DISPLAY 0.340426 (-7770 1957);
PAINT SKYBLUE (-7770 1957);
DISPLAY INVISIBLE (-7770 1957);
FORCEPROP 1 LAST PATH I29
J 0
(-7650 2000);
DISPLAY 0.872340 (-7650 2000);
PAINT AQUA (-7650 2000);
DISPLAY INVISIBLE (-7650 2000);
FORCEPROP 1 LAST SIZE 1B
J 0
(-7650 1950);
DISPLAY 1.170213 (-7650 1950);
PAINT AQUA (-7650 1950);
DISPLAY INVISIBLE (-7650 1950);
FORCEPROP 1 LAST HDL_POWER GND
J 0
(-7725 2150);
DISPLAY 1.170213 (-7725 2150);
PAINT GREEN (-7725 2150);
DISPLAY INVISIBLE (-7725 2150);
FORCEADD GND..1
(-6475 3450);
FORCEPROP 3 LASTPIN (-6475 3500) SIG_NAME GND\g
J 0
(-6465 3510);
DISPLAY 0.659574 (-6465 3510);
PAINT MONO (-6465 3510);
DISPLAY INVISIBLE (-6465 3510);
FORCEPROP 1 LAST PATH I3
J 0
(-6400 3450);
DISPLAY 0.872340 (-6400 3450);
PAINT AQUA (-6400 3450);
DISPLAY INVISIBLE (-6400 3450);
FORCEPROP 1 LAST VOLTAGE 0.0V
J 0
(-6520 3407);
DISPLAY 0.340426 (-6520 3407);
PAINT SKYBLUE (-6520 3407);
DISPLAY INVISIBLE (-6520 3407);
FORCEPROP 2 LAST CDS_LIB mstr_symbols
J 0
(-6475 3450);
PAINT ORANGE (-6475 3450);
DISPLAY INVISIBLE (-6475 3450);
FORCEPROP 1 LAST SIZE 1B
J 0
(-6400 3400);
DISPLAY 1.170213 (-6400 3400);
PAINT AQUA (-6400 3400);
DISPLAY INVISIBLE (-6400 3400);
FORCEPROP 1 LAST BODY_TYPE PLUMBING
J 0
(-6520 3407);
DISPLAY 0.340426 (-6520 3407);
PAINT GREEN (-6520 3407);
DISPLAY INVISIBLE (-6520 3407);
FORCEPROP 1 LAST HDL_POWER GND
J 0
(-6475 3600);
DISPLAY 1.170213 (-6475 3600);
PAINT GREEN (-6475 3600);
DISPLAY INVISIBLE (-6475 3600);
FORCEADD OFFPAGE..1
(-7650 2800);
FORCEPROP 2 LAST $XR0 181 
J 0
(-7902 2800);
DISPLAY 0.638298 (-7902 2800);
PAINT MONO (-7902 2800);
FORCEPROP 2 LAST $XR1 161 
J 0
(-8022 2800);
DISPLAY 0.638298 (-8022 2800);
PAINT MONO (-8022 2800);
FORCEPROP 2 LAST $XR2 191 
J 0
(-8142 2800);
DISPLAY 0.638298 (-8142 2800);
PAINT MONO (-8142 2800);
FORCEPROP 2 LAST CDS_LIB mstr_standard
J 0
(-7650 2800);
PAINT ORANGE (-7650 2800);
DISPLAY INVISIBLE (-7650 2800);
FORCEPROP 1 LAST COMMENT_BODY TRUE
J 0
(-7525 2700);
DISPLAY 1.170213 (-7525 2700);
PAINT PEACH (-7525 2700);
DISPLAY INVISIBLE (-7525 2700);
FORCEPROP 2 LAST PATH I32
J 0
(-7600 2875);
DISPLAY 1.021277 (-7600 2875);
PAINT ORANGE (-7600 2875);
DISPLAY INVISIBLE (-7600 2875);
FORCEPROP 1 LAST OFFPAGE TRUE
J 0
(-7325 2675);
DISPLAY 1.170213 (-7325 2675);
PAINT GREEN (-7325 2675);
DISPLAY INVISIBLE (-7325 2675);
FORCEADD CAP_A..1
(-1050 4400);
FORCEPROP 1 LASTPIN (-1050 4300) $PN 2
J 0
(-1040 4280);
DISPLAY 0.617021 (-1040 4280);
PAINT ORANGE (-1040 4280);
FORCEPROP 1 LASTPIN (-1050 4500) $PN 1
J 0
(-1040 4480);
DISPLAY 0.617021 (-1040 4480);
PAINT ORANGE (-1040 4480);
FORCEPROP 1 LAST MATERIAL X7R
J 0
(-1000 4300);
DISPLAY 0.617021 (-1000 4300);
PAINT SKYBLUE (-1000 4300);
FORCEPROP 1 LAST VOLTAGE 16V
J 0
(-1000 4400);
DISPLAY 0.617021 (-1000 4400);
PAINT SKYBLUE (-1000 4400);
FORCEPROP 1 LAST PACK_TYPE 0402V
J 0
(-1000 4200);
DISPLAY 0.617021 (-1000 4200);
PAINT SKYBLUE (-1000 4200);
FORCEPROP 1 LAST TOLERANCE 10%
J 0
(-1000 4350);
DISPLAY 0.617021 (-1000 4350);
PAINT SKYBLUE (-1000 4350);
FORCEPROP 1 LAST VALUE 0.1UF
J 0
(-1000 4450);
DISPLAY 0.617021 (-1000 4450);
PAINT SKYBLUE (-1000 4450);
FORCEPROP 1 LAST PART_NUMBER A36096-030
J 0
(-1000 4250);
DISPLAY 0.617021 (-1000 4250);
PAINT BLUE (-1000 4250);
FORCEPROP 1 LAST LOCATION C8B5
J 0
(-1000 4500);
DISPLAY 0.617021 (-1000 4500);
PAINT AQUA (-1000 4500);
FORCEPROP 2 LAST CDS_LIB dev_discrete
J 0
(-1050 4400);
PAINT ORANGE (-1050 4400);
DISPLAY INVISIBLE (-1050 4400);
FORCEPROP 2 LAST SEC 1
J 0
(-1000 4600);
DISPLAY 0.680851 (-1000 4600);
PAINT MONO (-1000 4600);
DISPLAY INVISIBLE (-1000 4600);
FORCEPROP 2 LAST SEC_TYPE 0402V
J 0
(-1000 4600);
DISPLAY 1.021277 (-1000 4600);
PAINT ORANGE (-1000 4600);
DISPLAY INVISIBLE (-1000 4600);
FORCEPROP 2 LAST CDS_SEC 1
J 0
(-1000 4550);
PAINT ORANGE (-1000 4550);
DISPLAY INVISIBLE (-1000 4550);
FORCEPROP 0 LAST BOM_COST PWR_SWITCH
J 0
(-1000 4700);
DISPLAY 1.021277 (-1000 4700);
PAINT ORANGE (-1000 4700);
DISPLAY INVISIBLE (-1000 4700);
FORCEPROP 2 LAST CDS_LOCATION C8B5
J 0
(-1000 4500);
DISPLAY 0.617021 (-1000 4500);
PAINT AQUA (-1000 4500);
DISPLAY INVISIBLE (-1000 4500);
FORCEPROP 0 LAST ROOM P5V_PWR_SWITCH
J 0
(-1000 4600);
DISPLAY 1.021277 (-1000 4600);
PAINT ORANGE (-1000 4600);
DISPLAY INVISIBLE (-1000 4600);
FORCEPROP 1 LAST PATH I37
J 0
(-1000 4550);
DISPLAY 0.978723 (-1000 4550);
PAINT WHITE (-1000 4550);
DISPLAY INVISIBLE (-1000 4550);
FORCEADD CAP..1
(-1375 4400);
FORCEPROP 1 LASTPIN (-1375 4300) $PN 2
J 0
(-1365 4280);
DISPLAY 0.617021 (-1365 4280);
PAINT ORANGE (-1365 4280);
FORCEPROP 1 LASTPIN (-1375 4500) $PN 1
J 0
(-1365 4480);
DISPLAY 0.617021 (-1365 4480);
PAINT ORANGE (-1365 4480);
FORCEPROP 1 LAST VOLTAGE 16V
J 0
(-1325 4400);
DISPLAY 0.617021 (-1325 4400);
PAINT SKYBLUE (-1325 4400);
FORCEPROP 1 LAST TOLERANCE 10%
J 0
(-1325 4350);
DISPLAY 0.617021 (-1325 4350);
PAINT SKYBLUE (-1325 4350);
FORCEPROP 1 LAST VALUE 10UF
J 0
(-1325 4450);
DISPLAY 0.617021 (-1325 4450);
PAINT SKYBLUE (-1325 4450);
FORCEPROP 1 LAST LOCATION C8B12
J 0
(-1325 4500);
DISPLAY 0.617021 (-1325 4500);
PAINT AQUA (-1325 4500);
FORCEPROP 1 LAST PACK_TYPE 0805
J 0
(-1325 4200);
DISPLAY 0.617021 (-1325 4200);
PAINT SKYBLUE (-1325 4200);
FORCEPROP 1 LAST MATERIAL X6S
J 0
(-1325 4300);
DISPLAY 0.617021 (-1325 4300);
PAINT SKYBLUE (-1325 4300);
FORCEPROP 1 LAST PART_NUMBER C95333-007
J 0
(-1325 4250);
DISPLAY 0.617021 (-1325 4250);
PAINT BLUE (-1325 4250);
FORCEPROP 2 LAST ROOM P5V_PWR_SWITCH
J 0
(-1325 4550);
DISPLAY 1.361702 (-1325 4550);
PAINT ORANGE (-1325 4550);
DISPLAY INVISIBLE (-1325 4550);
FORCEPROP 1 LAST PATH I38
J 0
(-1325 4550);
DISPLAY 0.978723 (-1325 4550);
PAINT WHITE (-1325 4550);
DISPLAY INVISIBLE (-1325 4550);
FORCEPROP 2 LAST CDS_LOCATION C8B12
J 0
(-1325 4500);
DISPLAY 0.617021 (-1325 4500);
PAINT AQUA (-1325 4500);
DISPLAY INVISIBLE (-1325 4500);
FORCEPROP 2 LAST CDS_LIB mstr_discrete
J 0
(-1375 4400);
PAINT ORANGE (-1375 4400);
DISPLAY INVISIBLE (-1375 4400);
FORCEPROP 2 LAST SEC 1
J 0
(-1325 4600);
DISPLAY 0.680851 (-1325 4600);
PAINT MONO (-1325 4600);
DISPLAY INVISIBLE (-1325 4600);
FORCEPROP 2 LAST SEC_TYPE 0805
J 0
(-1325 4600);
DISPLAY 1.021277 (-1325 4600);
PAINT ORANGE (-1325 4600);
DISPLAY INVISIBLE (-1325 4600);
FORCEADD GND..1
(-1200 4075);
FORCEPROP 3 LASTPIN (-1200 4125) SIG_NAME GND\g
J 0
(-1190 4135);
DISPLAY 0.659574 (-1190 4135);
PAINT MONO (-1190 4135);
DISPLAY INVISIBLE (-1190 4135);
FORCEPROP 1 LAST BODY_TYPE PLUMBING
J 0
(-1245 4032);
DISPLAY 0.340426 (-1245 4032);
PAINT GREEN (-1245 4032);
DISPLAY INVISIBLE (-1245 4032);
FORCEPROP 1 LAST SIZE 1B
J 0
(-1125 4025);
DISPLAY 1.170213 (-1125 4025);
PAINT AQUA (-1125 4025);
DISPLAY INVISIBLE (-1125 4025);
FORCEPROP 1 LAST VOLTAGE 0.0V
J 0
(-1245 4032);
DISPLAY 0.340426 (-1245 4032);
PAINT SKYBLUE (-1245 4032);
DISPLAY INVISIBLE (-1245 4032);
FORCEPROP 1 LAST PATH I39
J 0
(-1125 4075);
DISPLAY 0.872340 (-1125 4075);
PAINT AQUA (-1125 4075);
DISPLAY INVISIBLE (-1125 4075);
FORCEPROP 2 LAST CDS_LIB mstr_symbols
J 0
(-1200 4075);
PAINT ORANGE (-1200 4075);
DISPLAY INVISIBLE (-1200 4075);
FORCEPROP 1 LAST HDL_POWER GND
J 0
(-1200 4225);
DISPLAY 1.170213 (-1200 4225);
PAINT GREEN (-1200 4225);
DISPLAY INVISIBLE (-1200 4225);
FORCEADD CAP..1
(-1100 3250);
FORCEPROP 1 LASTPIN (-1100 3150) $PN 2
J 0
(-1090 3130);
DISPLAY 0.617021 (-1090 3130);
PAINT ORANGE (-1090 3130);
FORCEPROP 1 LAST MATERIAL X6S
J 0
(-1050 3150);
DISPLAY 0.617021 (-1050 3150);
PAINT SKYBLUE (-1050 3150);
FORCEPROP 1 LAST VOLTAGE 16V
J 0
(-1050 3250);
DISPLAY 0.617021 (-1050 3250);
PAINT SKYBLUE (-1050 3250);
FORCEPROP 1 LAST PACK_TYPE 0805
J 0
(-1050 3050);
DISPLAY 0.617021 (-1050 3050);
PAINT SKYBLUE (-1050 3050);
FORCEPROP 1 LAST TOLERANCE 10%
J 0
(-1050 3200);
DISPLAY 0.617021 (-1050 3200);
PAINT SKYBLUE (-1050 3200);
FORCEPROP 1 LAST VALUE 10UF
J 0
(-1050 3300);
DISPLAY 0.617021 (-1050 3300);
PAINT SKYBLUE (-1050 3300);
FORCEPROP 1 LAST PART_NUMBER C95333-007
J 0
(-1050 3100);
DISPLAY 0.617021 (-1050 3100);
PAINT BLUE (-1050 3100);
FORCEPROP 1 LAST LOCATION C8B6
J 0
(-1050 3350);
DISPLAY 0.617021 (-1050 3350);
PAINT AQUA (-1050 3350);
FORCEPROP 1 LASTPIN (-1100 3350) $PN 1
J 0
(-1090 3330);
DISPLAY 0.617021 (-1090 3330);
PAINT ORANGE (-1090 3330);
FORCEPROP 2 LAST CDS_LIB mstr_discrete
J 0
(-1100 3250);
PAINT ORANGE (-1100 3250);
DISPLAY INVISIBLE (-1100 3250);
FORCEPROP 2 LAST CDS_LOCATION C8B6
J 0
(-1050 3350);
DISPLAY 0.617021 (-1050 3350);
PAINT AQUA (-1050 3350);
DISPLAY INVISIBLE (-1050 3350);
FORCEPROP 1 LAST PATH I40
J 0
(-1050 3400);
DISPLAY 0.978723 (-1050 3400);
PAINT WHITE (-1050 3400);
DISPLAY INVISIBLE (-1050 3400);
FORCEPROP 2 LAST ROOM P5V_PWR_SWITCH
J 0
(-1050 3400);
DISPLAY 1.361702 (-1050 3400);
PAINT ORANGE (-1050 3400);
DISPLAY INVISIBLE (-1050 3400);
FORCEPROP 2 LAST SEC 1
J 0
(-1050 3450);
DISPLAY 0.680851 (-1050 3450);
PAINT MONO (-1050 3450);
DISPLAY INVISIBLE (-1050 3450);
FORCEPROP 2 LAST SEC_TYPE 0805
J 0
(-1050 3450);
DISPLAY 1.021277 (-1050 3450);
PAINT ORANGE (-1050 3450);
DISPLAY INVISIBLE (-1050 3450);
FORCEADD CAP_A..1
(-775 3250);
FORCEPROP 1 LAST PACK_TYPE 0402V
J 0
(-725 3050);
DISPLAY 0.617021 (-725 3050);
PAINT SKYBLUE (-725 3050);
FORCEPROP 1 LASTPIN (-775 3150) $PN 2
J 0
(-765 3130);
DISPLAY 0.617021 (-765 3130);
PAINT ORANGE (-765 3130);
FORCEPROP 1 LASTPIN (-775 3350) $PN 1
J 0
(-765 3330);
DISPLAY 0.617021 (-765 3330);
PAINT ORANGE (-765 3330);
FORCEPROP 1 LAST MATERIAL X7R
J 0
(-725 3150);
DISPLAY 0.617021 (-725 3150);
PAINT SKYBLUE (-725 3150);
FORCEPROP 1 LAST VOLTAGE 16V
J 0
(-725 3250);
DISPLAY 0.617021 (-725 3250);
PAINT SKYBLUE (-725 3250);
FORCEPROP 1 LAST TOLERANCE 10%
J 0
(-725 3200);
DISPLAY 0.617021 (-725 3200);
PAINT SKYBLUE (-725 3200);
FORCEPROP 1 LAST VALUE 0.1UF
J 0
(-725 3300);
DISPLAY 0.617021 (-725 3300);
PAINT SKYBLUE (-725 3300);
FORCEPROP 1 LAST PART_NUMBER A36096-030
J 0
(-725 3100);
DISPLAY 0.617021 (-725 3100);
PAINT BLUE (-725 3100);
FORCEPROP 1 LAST LOCATION C8B7
J 0
(-725 3350);
DISPLAY 0.617021 (-725 3350);
PAINT AQUA (-725 3350);
FORCEPROP 2 LAST CDS_LIB dev_discrete
J 0
(-775 3250);
PAINT ORANGE (-775 3250);
DISPLAY INVISIBLE (-775 3250);
FORCEPROP 1 LAST PATH I41
J 0
(-725 3400);
DISPLAY 0.978723 (-725 3400);
PAINT WHITE (-725 3400);
DISPLAY INVISIBLE (-725 3400);
FORCEPROP 0 LAST ROOM P5V_PWR_SWITCH
J 0
(-725 3450);
DISPLAY 1.021277 (-725 3450);
PAINT ORANGE (-725 3450);
DISPLAY INVISIBLE (-725 3450);
FORCEPROP 2 LAST CDS_LOCATION C8B7
J 0
(-725 3350);
DISPLAY 0.617021 (-725 3350);
PAINT AQUA (-725 3350);
DISPLAY INVISIBLE (-725 3350);
FORCEPROP 2 LAST CDS_SEC 1
J 0
(-725 3400);
PAINT ORANGE (-725 3400);
DISPLAY INVISIBLE (-725 3400);
FORCEPROP 2 LAST SEC_TYPE 0402V
J 0
(-725 3450);
DISPLAY 1.021277 (-725 3450);
PAINT ORANGE (-725 3450);
DISPLAY INVISIBLE (-725 3450);
FORCEPROP 2 LAST SEC 1
J 0
(-725 3450);
DISPLAY 0.680851 (-725 3450);
PAINT MONO (-725 3450);
DISPLAY INVISIBLE (-725 3450);
FORCEPROP 0 LAST BOM_COST PWR_SWITCH
J 0
(-725 3550);
DISPLAY 1.021277 (-725 3550);
PAINT ORANGE (-725 3550);
DISPLAY INVISIBLE (-725 3550);
FORCEADD GND..1
(-925 2900);
FORCEPROP 3 LASTPIN (-925 2950) SIG_NAME GND\g
J 0
(-915 2960);
DISPLAY 0.659574 (-915 2960);
PAINT MONO (-915 2960);
DISPLAY INVISIBLE (-915 2960);
FORCEPROP 1 LAST BODY_TYPE PLUMBING
J 0
(-970 2857);
DISPLAY 0.340426 (-970 2857);
PAINT GREEN (-970 2857);
DISPLAY INVISIBLE (-970 2857);
FORCEPROP 2 LAST CDS_LIB mstr_symbols
J 0
(-925 2900);
PAINT ORANGE (-925 2900);
DISPLAY INVISIBLE (-925 2900);
FORCEPROP 1 LAST VOLTAGE 0.0V
J 0
(-970 2857);
DISPLAY 0.340426 (-970 2857);
PAINT SKYBLUE (-970 2857);
DISPLAY INVISIBLE (-970 2857);
FORCEPROP 1 LAST SIZE 1B
J 0
(-850 2850);
DISPLAY 1.170213 (-850 2850);
PAINT AQUA (-850 2850);
DISPLAY INVISIBLE (-850 2850);
FORCEPROP 1 LAST PATH I42
J 0
(-850 2900);
DISPLAY 0.872340 (-850 2900);
PAINT AQUA (-850 2900);
DISPLAY INVISIBLE (-850 2900);
FORCEPROP 1 LAST HDL_POWER GND
J 0
(-925 3050);
DISPLAY 1.170213 (-925 3050);
PAINT GREEN (-925 3050);
DISPLAY INVISIBLE (-925 3050);
FORCEADD CAP_A..1
(-5050 4275);
FORCEPROP 1 LAST PACK_TYPE 0402V
J 0
(-5000 4075);
DISPLAY 0.617021 (-5000 4075);
PAINT SKYBLUE (-5000 4075);
FORCEPROP 1 LASTPIN (-5050 4175) $PN 2
J 0
(-5040 4155);
DISPLAY 0.617021 (-5040 4155);
PAINT ORANGE (-5040 4155);
FORCEPROP 1 LAST MATERIAL X7R
J 0
(-5000 4175);
DISPLAY 0.617021 (-5000 4175);
PAINT SKYBLUE (-5000 4175);
FORCEPROP 1 LAST TOLERANCE 10%
J 0
(-5000 4225);
DISPLAY 0.617021 (-5000 4225);
PAINT SKYBLUE (-5000 4225);
FORCEPROP 1 LAST VOLTAGE 16V
J 0
(-5000 4275);
DISPLAY 0.617021 (-5000 4275);
PAINT SKYBLUE (-5000 4275);
FORCEPROP 1 LASTPIN (-5050 4375) $PN 1
J 0
(-5040 4355);
DISPLAY 0.617021 (-5040 4355);
PAINT ORANGE (-5040 4355);
FORCEPROP 1 LAST LOCATION C2T36
J 0
(-5000 4375);
DISPLAY 0.617021 (-5000 4375);
PAINT AQUA (-5000 4375);
FORCEPROP 1 LAST VALUE 0.1UF
J 0
(-5000 4325);
DISPLAY 0.617021 (-5000 4325);
PAINT SKYBLUE (-5000 4325);
FORCEPROP 1 LAST PART_NUMBER A36096-030
J 0
(-5000 4125);
DISPLAY 0.617021 (-5000 4125);
PAINT BLUE (-5000 4125);
FORCEPROP 2 LAST CDS_LIB dev_discrete
J 0
(-5050 4275);
PAINT ORANGE (-5050 4275);
DISPLAY INVISIBLE (-5050 4275);
FORCEPROP 1 LAST PATH I43
J 0
(-5000 4425);
DISPLAY 0.978723 (-5000 4425);
PAINT WHITE (-5000 4425);
DISPLAY INVISIBLE (-5000 4425);
FORCEPROP 0 LAST ROOM P3V3_PWR_SWITCH
J 0
(-5000 4475);
DISPLAY 1.021277 (-5000 4475);
PAINT ORANGE (-5000 4475);
DISPLAY INVISIBLE (-5000 4475);
FORCEPROP 2 LAST CDS_LOCATION C2T36
J 0
(-5000 4375);
DISPLAY 0.617021 (-5000 4375);
PAINT AQUA (-5000 4375);
DISPLAY INVISIBLE (-5000 4375);
FORCEPROP 2 LAST CDS_SEC 1
J 0
(-5000 4425);
PAINT ORANGE (-5000 4425);
DISPLAY INVISIBLE (-5000 4425);
FORCEPROP 2 LAST SEC_TYPE 0402V
J 0
(-5000 4475);
DISPLAY 1.021277 (-5000 4475);
PAINT ORANGE (-5000 4475);
DISPLAY INVISIBLE (-5000 4475);
FORCEPROP 2 LAST SEC 1
J 0
(-5000 4475);
DISPLAY 0.680851 (-5000 4475);
PAINT MONO (-5000 4475);
DISPLAY INVISIBLE (-5000 4475);
FORCEPROP 0 LAST BOM_COST PWR_SWITCH
J 0
(-5000 4575);
DISPLAY 1.021277 (-5000 4575);
PAINT ORANGE (-5000 4575);
DISPLAY INVISIBLE (-5000 4575);
FORCEADD CAP..1
(-5375 4275);
FORCEPROP 1 LAST PACK_TYPE 0805
J 0
(-5325 4075);
DISPLAY 0.617021 (-5325 4075);
PAINT SKYBLUE (-5325 4075);
FORCEPROP 1 LASTPIN (-5375 4175) $PN 2
J 0
(-5365 4155);
DISPLAY 0.617021 (-5365 4155);
PAINT ORANGE (-5365 4155);
FORCEPROP 1 LAST VALUE 10UF
J 0
(-5325 4325);
DISPLAY 0.617021 (-5325 4325);
PAINT SKYBLUE (-5325 4325);
FORCEPROP 1 LAST VOLTAGE 16V
J 0
(-5325 4275);
DISPLAY 0.617021 (-5325 4275);
PAINT SKYBLUE (-5325 4275);
FORCEPROP 1 LAST LOCATION C2U1
J 0
(-5325 4375);
DISPLAY 0.617021 (-5325 4375);
PAINT AQUA (-5325 4375);
FORCEPROP 1 LASTPIN (-5375 4375) $PN 1
J 0
(-5365 4355);
DISPLAY 0.617021 (-5365 4355);
PAINT ORANGE (-5365 4355);
FORCEPROP 1 LAST PART_NUMBER C95333-007
J 0
(-5325 4125);
DISPLAY 0.617021 (-5325 4125);
PAINT BLUE (-5325 4125);
FORCEPROP 1 LAST MATERIAL X6S
J 0
(-5325 4175);
DISPLAY 0.617021 (-5325 4175);
PAINT SKYBLUE (-5325 4175);
FORCEPROP 1 LAST TOLERANCE 10%
J 0
(-5325 4225);
DISPLAY 0.617021 (-5325 4225);
PAINT SKYBLUE (-5325 4225);
FORCEPROP 2 LAST CDS_LIB mstr_discrete
J 0
(-5375 4275);
PAINT ORANGE (-5375 4275);
DISPLAY INVISIBLE (-5375 4275);
FORCEPROP 2 LAST SEC_TYPE 0805
J 0
(-5325 4475);
DISPLAY 1.021277 (-5325 4475);
PAINT ORANGE (-5325 4475);
DISPLAY INVISIBLE (-5325 4475);
FORCEPROP 2 LAST SEC 1
J 0
(-5325 4475);
DISPLAY 0.680851 (-5325 4475);
PAINT MONO (-5325 4475);
DISPLAY INVISIBLE (-5325 4475);
FORCEPROP 2 LAST CDS_LOCATION C2U1
J 0
(-5325 4375);
DISPLAY 0.617021 (-5325 4375);
PAINT AQUA (-5325 4375);
DISPLAY INVISIBLE (-5325 4375);
FORCEPROP 1 LAST PATH I44
J 0
(-5325 4425);
DISPLAY 0.978723 (-5325 4425);
PAINT WHITE (-5325 4425);
DISPLAY INVISIBLE (-5325 4425);
FORCEPROP 2 LAST ROOM P3V3_PWR_SWITCH
J 0
(-5325 4425);
DISPLAY 1.361702 (-5325 4425);
PAINT ORANGE (-5325 4425);
DISPLAY INVISIBLE (-5325 4425);
FORCEADD GND..1
(-5075 3925);
FORCEPROP 3 LASTPIN (-5075 3975) SIG_NAME GND\g
J 0
(-5065 3985);
DISPLAY 0.659574 (-5065 3985);
PAINT MONO (-5065 3985);
DISPLAY INVISIBLE (-5065 3985);
FORCEPROP 1 LAST BODY_TYPE PLUMBING
J 0
(-5120 3882);
DISPLAY 0.340426 (-5120 3882);
PAINT GREEN (-5120 3882);
DISPLAY INVISIBLE (-5120 3882);
FORCEPROP 1 LAST VOLTAGE 0.0V
J 0
(-5120 3882);
DISPLAY 0.340426 (-5120 3882);
PAINT SKYBLUE (-5120 3882);
DISPLAY INVISIBLE (-5120 3882);
FORCEPROP 1 LAST PATH I45
J 0
(-5000 3925);
DISPLAY 0.872340 (-5000 3925);
PAINT AQUA (-5000 3925);
DISPLAY INVISIBLE (-5000 3925);
FORCEPROP 1 LAST SIZE 1B
J 0
(-5000 3875);
DISPLAY 1.170213 (-5000 3875);
PAINT AQUA (-5000 3875);
DISPLAY INVISIBLE (-5000 3875);
FORCEPROP 2 LAST CDS_LIB mstr_symbols
J 0
(-5075 3925);
PAINT ORANGE (-5075 3925);
DISPLAY INVISIBLE (-5075 3925);
FORCEPROP 1 LAST HDL_POWER GND
J 0
(-5075 4075);
DISPLAY 1.170213 (-5075 4075);
PAINT GREEN (-5075 4075);
DISPLAY INVISIBLE (-5075 4075);
FORCEADD CAP_A..1
(-4675 3200);
FORCEPROP 1 LAST PACK_TYPE 0402V
J 0
(-4625 3000);
DISPLAY 0.617021 (-4625 3000);
PAINT SKYBLUE (-4625 3000);
FORCEPROP 1 LASTPIN (-4675 3100) $PN 2
J 0
(-4665 3080);
DISPLAY 0.617021 (-4665 3080);
PAINT ORANGE (-4665 3080);
FORCEPROP 1 LASTPIN (-4675 3300) $PN 1
J 0
(-4665 3280);
DISPLAY 0.617021 (-4665 3280);
PAINT ORANGE (-4665 3280);
FORCEPROP 1 LAST MATERIAL X7R
J 0
(-4625 3100);
DISPLAY 0.617021 (-4625 3100);
PAINT SKYBLUE (-4625 3100);
FORCEPROP 1 LAST VOLTAGE 16V
J 0
(-4625 3200);
DISPLAY 0.617021 (-4625 3200);
PAINT SKYBLUE (-4625 3200);
FORCEPROP 1 LAST TOLERANCE 10%
J 0
(-4625 3150);
DISPLAY 0.617021 (-4625 3150);
PAINT SKYBLUE (-4625 3150);
FORCEPROP 1 LAST VALUE 0.1UF
J 0
(-4625 3250);
DISPLAY 0.617021 (-4625 3250);
PAINT SKYBLUE (-4625 3250);
FORCEPROP 1 LAST LOCATION C2U19
J 0
(-4625 3300);
DISPLAY 0.617021 (-4625 3300);
PAINT AQUA (-4625 3300);
FORCEPROP 1 LAST PART_NUMBER A36096-030
J 0
(-4625 3050);
DISPLAY 0.617021 (-4625 3050);
PAINT BLUE (-4625 3050);
FORCEPROP 2 LAST CDS_LOCATION C2U19
J 0
(-4625 3300);
DISPLAY 0.617021 (-4625 3300);
PAINT AQUA (-4625 3300);
DISPLAY INVISIBLE (-4625 3300);
FORCEPROP 2 LAST CDS_LIB dev_discrete
J 0
(-4675 3200);
PAINT ORANGE (-4675 3200);
DISPLAY INVISIBLE (-4675 3200);
FORCEPROP 1 LAST PATH I46
J 0
(-4625 3350);
DISPLAY 0.978723 (-4625 3350);
PAINT WHITE (-4625 3350);
DISPLAY INVISIBLE (-4625 3350);
FORCEPROP 0 LAST ROOM P3V3_PWR_SWITCH
J 0
(-4625 3400);
DISPLAY 1.021277 (-4625 3400);
PAINT ORANGE (-4625 3400);
DISPLAY INVISIBLE (-4625 3400);
FORCEPROP 0 LAST BOM_COST PWR_SWITCH
J 0
(-4625 3500);
DISPLAY 1.021277 (-4625 3500);
PAINT ORANGE (-4625 3500);
DISPLAY INVISIBLE (-4625 3500);
FORCEPROP 2 LAST CDS_SEC 1
J 0
(-4625 3350);
PAINT ORANGE (-4625 3350);
DISPLAY INVISIBLE (-4625 3350);
FORCEPROP 2 LAST SEC_TYPE 0402V
J 0
(-4625 3400);
DISPLAY 1.021277 (-4625 3400);
PAINT ORANGE (-4625 3400);
DISPLAY INVISIBLE (-4625 3400);
FORCEPROP 2 LAST SEC 1
J 0
(-4625 3400);
DISPLAY 0.680851 (-4625 3400);
PAINT MONO (-4625 3400);
DISPLAY INVISIBLE (-4625 3400);
FORCEADD CAP..1
(-5000 3200);
FORCEPROP 1 LAST PACK_TYPE 0805
J 0
(-4950 3000);
DISPLAY 0.617021 (-4950 3000);
PAINT SKYBLUE (-4950 3000);
FORCEPROP 1 LASTPIN (-5000 3100) $PN 2
J 0
(-4990 3080);
DISPLAY 0.617021 (-4990 3080);
PAINT ORANGE (-4990 3080);
FORCEPROP 1 LASTPIN (-5000 3300) $PN 1
J 0
(-4990 3280);
DISPLAY 0.617021 (-4990 3280);
PAINT ORANGE (-4990 3280);
FORCEPROP 1 LAST MATERIAL X6S
J 0
(-4950 3100);
DISPLAY 0.617021 (-4950 3100);
PAINT SKYBLUE (-4950 3100);
FORCEPROP 1 LAST VOLTAGE 16V
J 0
(-4950 3200);
DISPLAY 0.617021 (-4950 3200);
PAINT SKYBLUE (-4950 3200);
FORCEPROP 1 LAST TOLERANCE 10%
J 0
(-4950 3150);
DISPLAY 0.617021 (-4950 3150);
PAINT SKYBLUE (-4950 3150);
FORCEPROP 1 LAST VALUE 10UF
J 0
(-4950 3250);
DISPLAY 0.617021 (-4950 3250);
PAINT SKYBLUE (-4950 3250);
FORCEPROP 1 LAST LOCATION C2U2
J 0
(-4950 3300);
DISPLAY 0.617021 (-4950 3300);
PAINT AQUA (-4950 3300);
FORCEPROP 1 LAST PART_NUMBER C95333-007
J 0
(-4950 3050);
DISPLAY 0.617021 (-4950 3050);
PAINT BLUE (-4950 3050);
FORCEPROP 2 LAST CDS_LIB mstr_discrete
J 0
(-5000 3200);
PAINT ORANGE (-5000 3200);
DISPLAY INVISIBLE (-5000 3200);
FORCEPROP 2 LAST CDS_LOCATION C2U2
J 0
(-4950 3300);
DISPLAY 0.617021 (-4950 3300);
PAINT AQUA (-4950 3300);
DISPLAY INVISIBLE (-4950 3300);
FORCEPROP 2 LAST SEC_TYPE 0805
J 0
(-4950 3400);
DISPLAY 1.021277 (-4950 3400);
PAINT ORANGE (-4950 3400);
DISPLAY INVISIBLE (-4950 3400);
FORCEPROP 2 LAST SEC 1
J 0
(-4950 3400);
DISPLAY 0.680851 (-4950 3400);
PAINT MONO (-4950 3400);
DISPLAY INVISIBLE (-4950 3400);
FORCEPROP 1 LAST PATH I47
J 0
(-4950 3350);
DISPLAY 0.978723 (-4950 3350);
PAINT WHITE (-4950 3350);
DISPLAY INVISIBLE (-4950 3350);
FORCEPROP 2 LAST ROOM P3V3_PWR_SWITCH
J 0
(-4950 3350);
DISPLAY 1.361702 (-4950 3350);
PAINT ORANGE (-4950 3350);
DISPLAY INVISIBLE (-4950 3350);
FORCEADD GND..1
(-4775 2850);
FORCEPROP 3 LASTPIN (-4775 2900) SIG_NAME GND\g
J 0
(-4765 2910);
DISPLAY 0.659574 (-4765 2910);
PAINT MONO (-4765 2910);
DISPLAY INVISIBLE (-4765 2910);
FORCEPROP 1 LAST BODY_TYPE PLUMBING
J 0
(-4820 2807);
DISPLAY 0.340426 (-4820 2807);
PAINT GREEN (-4820 2807);
DISPLAY INVISIBLE (-4820 2807);
FORCEPROP 1 LAST SIZE 1B
J 0
(-4700 2800);
DISPLAY 1.170213 (-4700 2800);
PAINT AQUA (-4700 2800);
DISPLAY INVISIBLE (-4700 2800);
FORCEPROP 1 LAST VOLTAGE 0.0V
J 0
(-4820 2807);
DISPLAY 0.340426 (-4820 2807);
PAINT SKYBLUE (-4820 2807);
DISPLAY INVISIBLE (-4820 2807);
FORCEPROP 2 LAST CDS_LIB mstr_symbols
J 0
(-4775 2850);
PAINT ORANGE (-4775 2850);
DISPLAY INVISIBLE (-4775 2850);
FORCEPROP 1 LAST HDL_POWER GND
J 0
(-4775 3000);
DISPLAY 1.170213 (-4775 3000);
PAINT GREEN (-4775 3000);
DISPLAY INVISIBLE (-4775 3000);
FORCEPROP 1 LAST PATH I48
J 0
(-4700 2850);
DISPLAY 0.872340 (-4700 2850);
PAINT AQUA (-4700 2850);
DISPLAY INVISIBLE (-4700 2850);
FORCEADD CAP_A..1
(-4675 1200);
FORCEPROP 1 LAST PACK_TYPE 0402V
J 0
(-4625 1000);
DISPLAY 0.617021 (-4625 1000);
PAINT SKYBLUE (-4625 1000);
FORCEPROP 1 LASTPIN (-4675 1100) $PN 2
J 0
(-4665 1080);
DISPLAY 0.617021 (-4665 1080);
PAINT ORANGE (-4665 1080);
FORCEPROP 1 LASTPIN (-4675 1300) $PN 1
J 0
(-4665 1280);
DISPLAY 0.617021 (-4665 1280);
PAINT ORANGE (-4665 1280);
FORCEPROP 1 LAST MATERIAL X7R
J 0
(-4625 1100);
DISPLAY 0.617021 (-4625 1100);
PAINT SKYBLUE (-4625 1100);
FORCEPROP 1 LAST VOLTAGE 16V
J 0
(-4625 1200);
DISPLAY 0.617021 (-4625 1200);
PAINT SKYBLUE (-4625 1200);
FORCEPROP 1 LAST TOLERANCE 10%
J 0
(-4625 1150);
DISPLAY 0.617021 (-4625 1150);
PAINT SKYBLUE (-4625 1150);
FORCEPROP 1 LAST VALUE 0.1UF
J 0
(-4625 1250);
DISPLAY 0.617021 (-4625 1250);
PAINT SKYBLUE (-4625 1250);
FORCEPROP 1 LAST PART_NUMBER A36096-030
J 0
(-4625 1050);
DISPLAY 0.617021 (-4625 1050);
PAINT BLUE (-4625 1050);
FORCEPROP 1 LAST LOCATION C7E9
J 0
(-4625 1300);
DISPLAY 0.617021 (-4625 1300);
PAINT AQUA (-4625 1300);
FORCEPROP 2 LAST CDS_LIB dev_discrete
J 0
(-4675 1200);
PAINT ORANGE (-4675 1200);
DISPLAY INVISIBLE (-4675 1200);
FORCEPROP 1 LAST PATH I49
J 0
(-4625 1350);
DISPLAY 0.978723 (-4625 1350);
PAINT WHITE (-4625 1350);
DISPLAY INVISIBLE (-4625 1350);
FORCEPROP 2 LAST CDS_LOCATION C7E9
J 0
(-4625 1300);
DISPLAY 0.617021 (-4625 1300);
PAINT AQUA (-4625 1300);
DISPLAY INVISIBLE (-4625 1300);
FORCEPROP 2 LAST CDS_SEC 1
J 0
(-4625 1350);
PAINT ORANGE (-4625 1350);
DISPLAY INVISIBLE (-4625 1350);
FORCEPROP 0 LAST ROOM P12V_PWR_SWITCH
J 0
(-4625 1400);
DISPLAY 1.021277 (-4625 1400);
PAINT ORANGE (-4625 1400);
DISPLAY INVISIBLE (-4625 1400);
FORCEPROP 2 LAST SEC_TYPE 0402V
J 0
(-4625 1400);
DISPLAY 1.021277 (-4625 1400);
PAINT ORANGE (-4625 1400);
DISPLAY INVISIBLE (-4625 1400);
FORCEPROP 2 LAST SEC 1
J 0
(-4625 1400);
DISPLAY 0.680851 (-4625 1400);
PAINT MONO (-4625 1400);
DISPLAY INVISIBLE (-4625 1400);
FORCEPROP 0 LAST BOM_COST PWR_SWITCH
J 0
(-4625 1500);
DISPLAY 1.021277 (-4625 1500);
PAINT ORANGE (-4625 1500);
DISPLAY INVISIBLE (-4625 1500);
FORCEADD CAP..1
(-5125 1250);
FORCEPROP 1 LASTPIN (-5125 1150) $PN 2
J 0
(-5115 1130);
DISPLAY 0.617021 (-5115 1130);
PAINT ORANGE (-5115 1130);
FORCEPROP 1 LAST MATERIAL X6S
J 0
(-5075 1150);
DISPLAY 0.617021 (-5075 1150);
PAINT SKYBLUE (-5075 1150);
FORCEPROP 1 LAST VOLTAGE 16V
J 0
(-5075 1250);
DISPLAY 0.617021 (-5075 1250);
PAINT SKYBLUE (-5075 1250);
FORCEPROP 1 LAST PACK_TYPE 0805
J 0
(-5075 1050);
DISPLAY 0.617021 (-5075 1050);
PAINT SKYBLUE (-5075 1050);
FORCEPROP 1 LAST TOLERANCE 10%
J 0
(-5075 1200);
DISPLAY 0.617021 (-5075 1200);
PAINT SKYBLUE (-5075 1200);
FORCEPROP 1 LAST VALUE 10UF
J 0
(-5075 1300);
DISPLAY 0.617021 (-5075 1300);
PAINT SKYBLUE (-5075 1300);
FORCEPROP 1 LASTPIN (-5125 1350) $PN 1
J 0
(-5115 1330);
DISPLAY 0.617021 (-5115 1330);
PAINT ORANGE (-5115 1330);
FORCEPROP 1 LAST LOCATION C7E8
J 0
(-5075 1350);
DISPLAY 0.617021 (-5075 1350);
PAINT AQUA (-5075 1350);
FORCEPROP 1 LAST PART_NUMBER C95333-007
J 0
(-5075 1100);
DISPLAY 0.617021 (-5075 1100);
PAINT BLUE (-5075 1100);
FORCEPROP 2 LAST CDS_LIB mstr_discrete
J 0
(-5125 1250);
PAINT ORANGE (-5125 1250);
DISPLAY INVISIBLE (-5125 1250);
FORCEPROP 2 LAST SEC_TYPE 0805
J 0
(-5075 1450);
DISPLAY 1.021277 (-5075 1450);
PAINT ORANGE (-5075 1450);
DISPLAY INVISIBLE (-5075 1450);
FORCEPROP 2 LAST SEC 1
J 0
(-5075 1450);
DISPLAY 0.680851 (-5075 1450);
PAINT MONO (-5075 1450);
DISPLAY INVISIBLE (-5075 1450);
FORCEPROP 2 LAST CDS_LOCATION C7E8
J 0
(-5075 1350);
DISPLAY 0.617021 (-5075 1350);
PAINT AQUA (-5075 1350);
DISPLAY INVISIBLE (-5075 1350);
FORCEPROP 1 LAST PATH I50
J 0
(-5075 1400);
DISPLAY 0.978723 (-5075 1400);
PAINT WHITE (-5075 1400);
DISPLAY INVISIBLE (-5075 1400);
FORCEPROP 2 LAST ROOM P12V_PWR_SWITCH
J 0
(-5075 1400);
DISPLAY 1.361702 (-5075 1400);
PAINT ORANGE (-5075 1400);
DISPLAY INVISIBLE (-5075 1400);
FORCEADD GND..1
(-5125 925);
FORCEPROP 3 LASTPIN (-5125 975) SIG_NAME GND\g
J 0
(-5115 985);
DISPLAY 0.659574 (-5115 985);
PAINT MONO (-5115 985);
DISPLAY INVISIBLE (-5115 985);
FORCEPROP 1 LAST BODY_TYPE PLUMBING
J 0
(-5170 882);
DISPLAY 0.340426 (-5170 882);
PAINT GREEN (-5170 882);
DISPLAY INVISIBLE (-5170 882);
FORCEPROP 2 LAST CDS_LIB mstr_symbols
J 0
(-5125 925);
PAINT ORANGE (-5125 925);
DISPLAY INVISIBLE (-5125 925);
FORCEPROP 1 LAST VOLTAGE 0.0V
J 0
(-5170 882);
DISPLAY 0.340426 (-5170 882);
PAINT SKYBLUE (-5170 882);
DISPLAY INVISIBLE (-5170 882);
FORCEPROP 1 LAST HDL_POWER GND
J 0
(-5125 1075);
DISPLAY 1.170213 (-5125 1075);
PAINT GREEN (-5125 1075);
DISPLAY INVISIBLE (-5125 1075);
FORCEPROP 1 LAST PATH I51
J 0
(-5050 925);
DISPLAY 0.872340 (-5050 925);
PAINT AQUA (-5050 925);
DISPLAY INVISIBLE (-5050 925);
FORCEPROP 1 LAST SIZE 1B
J 0
(-5050 875);
DISPLAY 1.170213 (-5050 875);
PAINT AQUA (-5050 875);
DISPLAY INVISIBLE (-5050 875);
FORCEADD CAP_A..1
(-4775 2250);
FORCEPROP 1 LASTPIN (-4775 2150) $PN 2
J 0
(-4765 2130);
DISPLAY 0.617021 (-4765 2130);
PAINT ORANGE (-4765 2130);
FORCEPROP 1 LAST MATERIAL X7R
J 0
(-4725 2150);
DISPLAY 0.617021 (-4725 2150);
PAINT SKYBLUE (-4725 2150);
FORCEPROP 1 LAST VOLTAGE 16V
J 0
(-4725 2250);
DISPLAY 0.617021 (-4725 2250);
PAINT SKYBLUE (-4725 2250);
FORCEPROP 1 LAST TOLERANCE 10%
J 0
(-4725 2200);
DISPLAY 0.617021 (-4725 2200);
PAINT SKYBLUE (-4725 2200);
FORCEPROP 1 LASTPIN (-4775 2350) $PN 1
J 0
(-4765 2330);
DISPLAY 0.617021 (-4765 2330);
PAINT ORANGE (-4765 2330);
FORCEPROP 1 LAST LOCATION C7E5
J 0
(-4725 2350);
DISPLAY 0.617021 (-4725 2350);
PAINT AQUA (-4725 2350);
FORCEPROP 1 LAST PACK_TYPE 0402V
J 0
(-4725 2050);
DISPLAY 0.617021 (-4725 2050);
PAINT SKYBLUE (-4725 2050);
FORCEPROP 1 LAST VALUE 0.1UF
J 0
(-4725 2300);
DISPLAY 0.617021 (-4725 2300);
PAINT SKYBLUE (-4725 2300);
FORCEPROP 1 LAST PART_NUMBER A36096-030
J 0
(-4725 2100);
DISPLAY 0.617021 (-4725 2100);
PAINT BLUE (-4725 2100);
FORCEPROP 2 LAST CDS_LIB dev_discrete
J 0
(-4775 2250);
PAINT ORANGE (-4775 2250);
DISPLAY INVISIBLE (-4775 2250);
FORCEPROP 0 LAST ROOM P12V_PWR_SWITCH
J 0
(-4725 2450);
DISPLAY 1.021277 (-4725 2450);
PAINT ORANGE (-4725 2450);
DISPLAY INVISIBLE (-4725 2450);
FORCEPROP 1 LAST PATH I52
J 0
(-4725 2400);
DISPLAY 0.978723 (-4725 2400);
PAINT WHITE (-4725 2400);
DISPLAY INVISIBLE (-4725 2400);
FORCEPROP 2 LAST CDS_LOCATION C7E5
J 0
(-4725 2350);
DISPLAY 0.617021 (-4725 2350);
PAINT AQUA (-4725 2350);
DISPLAY INVISIBLE (-4725 2350);
FORCEPROP 2 LAST CDS_SEC 1
J 0
(-4725 2400);
PAINT ORANGE (-4725 2400);
DISPLAY INVISIBLE (-4725 2400);
FORCEPROP 2 LAST SEC_TYPE 0402V
J 0
(-4725 2450);
DISPLAY 1.021277 (-4725 2450);
PAINT ORANGE (-4725 2450);
DISPLAY INVISIBLE (-4725 2450);
FORCEPROP 2 LAST SEC 1
J 0
(-4725 2450);
DISPLAY 0.680851 (-4725 2450);
PAINT MONO (-4725 2450);
DISPLAY INVISIBLE (-4725 2450);
FORCEPROP 0 LAST BOM_COST PWR_SWITCH
J 0
(-4725 2550);
DISPLAY 1.021277 (-4725 2550);
PAINT ORANGE (-4725 2550);
DISPLAY INVISIBLE (-4725 2550);
FORCEADD CAP..1
(-5100 2250);
FORCEPROP 1 LASTPIN (-5100 2150) $PN 2
J 0
(-5090 2130);
DISPLAY 0.617021 (-5090 2130);
PAINT ORANGE (-5090 2130);
FORCEPROP 1 LAST MATERIAL X6S
J 0
(-5050 2150);
DISPLAY 0.617021 (-5050 2150);
PAINT SKYBLUE (-5050 2150);
FORCEPROP 1 LAST VOLTAGE 16V
J 0
(-5050 2250);
DISPLAY 0.617021 (-5050 2250);
PAINT SKYBLUE (-5050 2250);
FORCEPROP 1 LAST TOLERANCE 10%
J 0
(-5050 2200);
DISPLAY 0.617021 (-5050 2200);
PAINT SKYBLUE (-5050 2200);
FORCEPROP 1 LAST PACK_TYPE 0805
J 0
(-5050 2050);
DISPLAY 0.617021 (-5050 2050);
PAINT SKYBLUE (-5050 2050);
FORCEPROP 1 LAST VALUE 10UF
J 0
(-5050 2300);
DISPLAY 0.617021 (-5050 2300);
PAINT SKYBLUE (-5050 2300);
FORCEPROP 1 LASTPIN (-5100 2350) $PN 1
J 0
(-5090 2330);
DISPLAY 0.617021 (-5090 2330);
PAINT ORANGE (-5090 2330);
FORCEPROP 1 LAST LOCATION C7E6
J 0
(-5050 2350);
DISPLAY 0.617021 (-5050 2350);
PAINT AQUA (-5050 2350);
FORCEPROP 1 LAST PART_NUMBER C95333-007
J 0
(-5050 2100);
DISPLAY 0.617021 (-5050 2100);
PAINT BLUE (-5050 2100);
FORCEPROP 2 LAST CDS_LIB mstr_discrete
J 0
(-5100 2250);
PAINT ORANGE (-5100 2250);
DISPLAY INVISIBLE (-5100 2250);
FORCEPROP 2 LAST ROOM P12V_PWR_SWITCH
J 0
(-5050 2400);
DISPLAY 1.361702 (-5050 2400);
PAINT ORANGE (-5050 2400);
DISPLAY INVISIBLE (-5050 2400);
FORCEPROP 1 LAST PATH I53
J 0
(-5050 2400);
DISPLAY 0.978723 (-5050 2400);
PAINT WHITE (-5050 2400);
DISPLAY INVISIBLE (-5050 2400);
FORCEPROP 2 LAST CDS_LOCATION C7E6
J 0
(-5050 2350);
DISPLAY 0.617021 (-5050 2350);
PAINT AQUA (-5050 2350);
DISPLAY INVISIBLE (-5050 2350);
FORCEPROP 2 LAST SEC 1
J 0
(-5050 2450);
DISPLAY 0.680851 (-5050 2450);
PAINT MONO (-5050 2450);
DISPLAY INVISIBLE (-5050 2450);
FORCEPROP 2 LAST SEC_TYPE 0805
J 0
(-5050 2450);
DISPLAY 1.021277 (-5050 2450);
PAINT ORANGE (-5050 2450);
DISPLAY INVISIBLE (-5050 2450);
FORCEADD GND..1
(-4800 1900);
FORCEPROP 3 LASTPIN (-4800 1950) SIG_NAME GND\g
J 0
(-4790 1960);
DISPLAY 0.659574 (-4790 1960);
PAINT MONO (-4790 1960);
DISPLAY INVISIBLE (-4790 1960);
FORCEPROP 1 LAST VOLTAGE 0.0V
J 0
(-4845 1857);
DISPLAY 0.340426 (-4845 1857);
PAINT SKYBLUE (-4845 1857);
DISPLAY INVISIBLE (-4845 1857);
FORCEPROP 1 LAST BODY_TYPE PLUMBING
J 0
(-4845 1857);
DISPLAY 0.340426 (-4845 1857);
PAINT GREEN (-4845 1857);
DISPLAY INVISIBLE (-4845 1857);
FORCEPROP 2 LAST CDS_LIB mstr_symbols
J 0
(-4800 1900);
PAINT ORANGE (-4800 1900);
DISPLAY INVISIBLE (-4800 1900);
FORCEPROP 1 LAST SIZE 1B
J 0
(-4725 1850);
DISPLAY 1.170213 (-4725 1850);
PAINT AQUA (-4725 1850);
DISPLAY INVISIBLE (-4725 1850);
FORCEPROP 1 LAST PATH I54
J 0
(-4725 1900);
DISPLAY 0.872340 (-4725 1900);
PAINT AQUA (-4725 1900);
DISPLAY INVISIBLE (-4725 1900);
FORCEPROP 1 LAST HDL_POWER GND
J 0
(-4800 2050);
DISPLAY 1.170213 (-4800 2050);
PAINT GREEN (-4800 2050);
DISPLAY INVISIBLE (-4800 2050);
FORCEADD OFFPAGE..1
(-7925 3875);
FORCEPROP 2 LAST $XR0 191 
J 0
(-8207 3875);
DISPLAY 0.638298 (-8207 3875);
PAINT MONO (-8207 3875);
FORCEPROP 2 LAST PATH I58
J 0
(-7875 3950);
DISPLAY 1.021277 (-7875 3950);
PAINT ORANGE (-7875 3950);
DISPLAY INVISIBLE (-7875 3950);
FORCEPROP 1 LAST COMMENT_BODY TRUE
J 0
(-7800 3775);
DISPLAY 1.170213 (-7800 3775);
PAINT PEACH (-7800 3775);
DISPLAY INVISIBLE (-7800 3775);
FORCEPROP 2 LAST CDS_LIB mstr_standard
J 0
(-7925 3875);
PAINT ORANGE (-7925 3875);
DISPLAY INVISIBLE (-7925 3875);
FORCEPROP 1 LAST OFFPAGE TRUE
J 0
(-7600 3750);
DISPLAY 1.170213 (-7600 3750);
PAINT GREEN (-7600 3750);
DISPLAY INVISIBLE (-7600 3750);
FORCEADD OFFPAGE..1
(-7925 1900);
FORCEPROP 2 LAST $XR0 191 
J 0
(-8207 1900);
DISPLAY 0.638298 (-8207 1900);
PAINT MONO (-8207 1900);
FORCEPROP 2 LAST PATH I59
J 0
(-7875 1975);
DISPLAY 1.021277 (-7875 1975);
PAINT ORANGE (-7875 1975);
DISPLAY INVISIBLE (-7875 1975);
FORCEPROP 1 LAST COMMENT_BODY TRUE
J 0
(-7800 1800);
DISPLAY 1.170213 (-7800 1800);
PAINT PEACH (-7800 1800);
DISPLAY INVISIBLE (-7800 1800);
FORCEPROP 2 LAST CDS_LIB mstr_standard
J 0
(-7925 1900);
PAINT ORANGE (-7925 1900);
DISPLAY INVISIBLE (-7925 1900);
FORCEPROP 1 LAST OFFPAGE TRUE
J 0
(-7600 1775);
DISPLAY 1.170213 (-7600 1775);
PAINT GREEN (-7600 1775);
DISPLAY INVISIBLE (-7600 1775);
FORCEADD P3V3_STBY..1
(-5600 4600);
FORCEPROP 3 LASTPIN (-5600 4550) SIG_NAME P3V3_STBY\g
J 0
(-5590 4560);
DISPLAY 0.659574 (-5590 4560);
PAINT MONO (-5590 4560);
DISPLAY INVISIBLE (-5590 4560);
FORCEPROP 1 LAST HDL_POWER P3V3_STBY
J 0
(-5900 4475);
DISPLAY 0.872340 (-5900 4475);
PAINT ORANGE (-5900 4475);
DISPLAY INVISIBLE (-5900 4475);
FORCEPROP 1 LAST BODY_TYPE PLUMBING
J 0
(-5645 4557);
DISPLAY 0.340426 (-5645 4557);
PAINT GREEN (-5645 4557);
DISPLAY INVISIBLE (-5645 4557);
FORCEPROP 1 LAST VOLTAGE 3.3V
J 0
(-5645 4557);
DISPLAY 0.340426 (-5645 4557);
PAINT SKYBLUE (-5645 4557);
DISPLAY INVISIBLE (-5645 4557);
FORCEPROP 1 LAST PATH I6
J 0
(-5555 4602);
DISPLAY 0.340426 (-5555 4602);
PAINT GREEN (-5555 4602);
DISPLAY INVISIBLE (-5555 4602);
FORCEPROP 2 LAST CDS_LIB mstr_symbols
J 0
(-5600 4600);
PAINT ORANGE (-5600 4600);
DISPLAY INVISIBLE (-5600 4600);
FORCEPROP 1 LAST SIZE 1B
J 0
(-5555 4622);
DISPLAY 0.340426 (-5555 4622);
PAINT GREEN (-5555 4622);
DISPLAY INVISIBLE (-5555 4622);
FORCEADD CAP..1
(-1175 1225);
FORCEPROP 1 LASTPIN (-1175 1125) $PN 2
J 0
(-1165 1105);
DISPLAY 0.617021 (-1165 1105);
PAINT ORANGE (-1165 1105);
FORCEPROP 1 LAST MATERIAL X6S
J 0
(-1125 1125);
DISPLAY 0.617021 (-1125 1125);
PAINT SKYBLUE (-1125 1125);
FORCEPROP 1 LAST VOLTAGE 16V
J 0
(-1125 1225);
DISPLAY 0.617021 (-1125 1225);
PAINT SKYBLUE (-1125 1225);
FORCEPROP 1 LAST TOLERANCE 10%
J 0
(-1125 1175);
DISPLAY 0.617021 (-1125 1175);
PAINT SKYBLUE (-1125 1175);
FORCEPROP 1 LASTPIN (-1175 1325) $PN 1
J 0
(-1165 1305);
DISPLAY 0.617021 (-1165 1305);
PAINT ORANGE (-1165 1305);
FORCEPROP 1 LAST PACK_TYPE 0805
J 0
(-1125 1025);
DISPLAY 0.617021 (-1125 1025);
PAINT SKYBLUE (-1125 1025);
FORCEPROP 1 LAST VALUE 10UF
J 0
(-1125 1275);
DISPLAY 0.617021 (-1125 1275);
PAINT SKYBLUE (-1125 1275);
FORCEPROP 1 LAST PART_NUMBER C95333-007
J 0
(-1125 1075);
DISPLAY 0.617021 (-1125 1075);
PAINT BLUE (-1125 1075);
FORCEPROP 1 LAST LOCATION C1B18
J 0
(-1125 1325);
DISPLAY 0.617021 (-1125 1325);
PAINT AQUA (-1125 1325);
FORCEPROP 2 LAST CDS_LIB mstr_discrete
J 0
(-1175 1225);
PAINT ORANGE (-1175 1225);
DISPLAY INVISIBLE (-1175 1225);
FORCEPROP 2 LAST ROOM P12V_FAN_PWR_SWITCH
J 0
(-1125 1375);
DISPLAY 1.361702 (-1125 1375);
PAINT ORANGE (-1125 1375);
DISPLAY INVISIBLE (-1125 1375);
FORCEPROP 1 LAST PATH I61
J 0
(-1125 1375);
DISPLAY 0.978723 (-1125 1375);
PAINT WHITE (-1125 1375);
DISPLAY INVISIBLE (-1125 1375);
FORCEPROP 2 LAST CDS_LOCATION C1B18
J 0
(-1125 1325);
DISPLAY 0.617021 (-1125 1325);
PAINT AQUA (-1125 1325);
DISPLAY INVISIBLE (-1125 1325);
FORCEPROP 2 LAST SEC 1
J 0
(-1125 1425);
DISPLAY 0.680851 (-1125 1425);
PAINT MONO (-1125 1425);
DISPLAY INVISIBLE (-1125 1425);
FORCEPROP 2 LAST SEC_TYPE 0805
J 0
(-1125 1425);
DISPLAY 1.021277 (-1125 1425);
PAINT ORANGE (-1125 1425);
DISPLAY INVISIBLE (-1125 1425);
FORCEADD GND..1
(-1175 900);
FORCEPROP 3 LASTPIN (-1175 950) SIG_NAME GND\g
J 0
(-1165 960);
DISPLAY 0.659574 (-1165 960);
PAINT MONO (-1165 960);
DISPLAY INVISIBLE (-1165 960);
FORCEPROP 1 LAST BODY_TYPE PLUMBING
J 0
(-1220 857);
DISPLAY 0.340426 (-1220 857);
PAINT GREEN (-1220 857);
DISPLAY INVISIBLE (-1220 857);
FORCEPROP 1 LAST VOLTAGE 0.0V
J 0
(-1220 857);
DISPLAY 0.340426 (-1220 857);
PAINT SKYBLUE (-1220 857);
DISPLAY INVISIBLE (-1220 857);
FORCEPROP 2 LAST CDS_LIB mstr_symbols
J 0
(-1175 900);
PAINT ORANGE (-1175 900);
DISPLAY INVISIBLE (-1175 900);
FORCEPROP 1 LAST SIZE 1B
J 0
(-1100 850);
DISPLAY 1.170213 (-1100 850);
PAINT AQUA (-1100 850);
DISPLAY INVISIBLE (-1100 850);
FORCEPROP 1 LAST PATH I63
J 0
(-1100 900);
DISPLAY 0.872340 (-1100 900);
PAINT AQUA (-1100 900);
DISPLAY INVISIBLE (-1100 900);
FORCEPROP 1 LAST HDL_POWER GND
J 0
(-1175 1050);
DISPLAY 1.170213 (-1175 1050);
PAINT GREEN (-1175 1050);
DISPLAY INVISIBLE (-1175 1050);
FORCEADD CAP_A..1
(-725 1225);
FORCEPROP 1 LASTPIN (-725 1125) $PN 2
J 0
(-715 1105);
DISPLAY 0.617021 (-715 1105);
PAINT ORANGE (-715 1105);
FORCEPROP 1 LAST MATERIAL X7R
J 0
(-675 1125);
DISPLAY 0.617021 (-675 1125);
PAINT SKYBLUE (-675 1125);
FORCEPROP 1 LAST VOLTAGE 16V
J 0
(-675 1225);
DISPLAY 0.617021 (-675 1225);
PAINT SKYBLUE (-675 1225);
FORCEPROP 1 LAST PACK_TYPE 0402V
J 0
(-675 1025);
DISPLAY 0.617021 (-675 1025);
PAINT SKYBLUE (-675 1025);
FORCEPROP 1 LAST TOLERANCE 10%
J 0
(-675 1175);
DISPLAY 0.617021 (-675 1175);
PAINT SKYBLUE (-675 1175);
FORCEPROP 1 LAST VALUE 0.1UF
J 0
(-675 1275);
DISPLAY 0.617021 (-675 1275);
PAINT SKYBLUE (-675 1275);
FORCEPROP 1 LASTPIN (-725 1325) $PN 1
J 0
(-715 1305);
DISPLAY 0.617021 (-715 1305);
PAINT ORANGE (-715 1305);
FORCEPROP 1 LAST LOCATION C1B19
J 0
(-675 1325);
DISPLAY 0.617021 (-675 1325);
PAINT AQUA (-675 1325);
FORCEPROP 1 LAST PART_NUMBER A36096-030
J 0
(-675 1075);
DISPLAY 0.617021 (-675 1075);
PAINT BLUE (-675 1075);
FORCEPROP 2 LAST CDS_LIB dev_discrete
J 0
(-725 1225);
PAINT ORANGE (-725 1225);
DISPLAY INVISIBLE (-725 1225);
FORCEPROP 2 LAST CDS_LOCATION C1B19
J 0
(-675 1325);
DISPLAY 0.617021 (-675 1325);
PAINT AQUA (-675 1325);
DISPLAY INVISIBLE (-675 1325);
FORCEPROP 2 LAST CDS_SEC 1
J 0
(-675 1375);
PAINT ORANGE (-675 1375);
DISPLAY INVISIBLE (-675 1375);
FORCEPROP 1 LAST PATH I64
J 0
(-675 1375);
DISPLAY 0.978723 (-675 1375);
PAINT WHITE (-675 1375);
DISPLAY INVISIBLE (-675 1375);
FORCEPROP 2 LAST SEC 1
J 0
(-675 1425);
DISPLAY 0.680851 (-675 1425);
PAINT MONO (-675 1425);
DISPLAY INVISIBLE (-675 1425);
FORCEPROP 2 LAST SEC_TYPE 0402V
J 0
(-675 1425);
DISPLAY 1.021277 (-675 1425);
PAINT ORANGE (-675 1425);
DISPLAY INVISIBLE (-675 1425);
FORCEPROP 0 LAST ROOM P12V_FAN_PWR_SWITCH
J 0
(-675 1425);
DISPLAY 1.021277 (-675 1425);
PAINT ORANGE (-675 1425);
DISPLAY INVISIBLE (-675 1425);
FORCEPROP 0 LAST BOM_COST PWR_SWITCH
J 0
(-675 1525);
DISPLAY 1.021277 (-675 1525);
PAINT ORANGE (-675 1525);
DISPLAY INVISIBLE (-675 1525);
FORCEADD OFFPAGE..1
(-3975 1875);
FORCEPROP 2 LAST $XR0 161 
J 0
(-4227 1875);
DISPLAY 0.638298 (-4227 1875);
PAINT MONO (-4227 1875);
FORCEPROP 2 LAST $XR1 181 
J 0
(-4347 1875);
DISPLAY 0.638298 (-4347 1875);
PAINT MONO (-4347 1875);
FORCEPROP 2 LAST PATH I65
J 0
(-3925 1950);
DISPLAY 1.021277 (-3925 1950);
PAINT ORANGE (-3925 1950);
DISPLAY INVISIBLE (-3925 1950);
FORCEPROP 1 LAST COMMENT_BODY TRUE
J 0
(-3850 1775);
DISPLAY 1.170213 (-3850 1775);
PAINT PEACH (-3850 1775);
DISPLAY INVISIBLE (-3850 1775);
FORCEPROP 2 LAST CDS_LIB mstr_standard
J 0
(-3975 1875);
PAINT ORANGE (-3975 1875);
DISPLAY INVISIBLE (-3975 1875);
FORCEPROP 1 LAST OFFPAGE TRUE
J 0
(-3650 1750);
DISPLAY 1.170213 (-3650 1750);
PAINT GREEN (-3650 1750);
DISPLAY INVISIBLE (-3650 1750);
FORCEADD GND..1
(-3775 1950);
FORCEPROP 3 LASTPIN (-3775 2000) SIG_NAME GND\g
J 0
(-3765 2010);
DISPLAY 0.659574 (-3765 2010);
PAINT MONO (-3765 2010);
DISPLAY INVISIBLE (-3765 2010);
FORCEPROP 1 LAST PATH I66
J 0
(-3700 1950);
DISPLAY 0.872340 (-3700 1950);
PAINT AQUA (-3700 1950);
DISPLAY INVISIBLE (-3700 1950);
FORCEPROP 1 LAST BODY_TYPE PLUMBING
J 0
(-3820 1907);
DISPLAY 0.340426 (-3820 1907);
PAINT GREEN (-3820 1907);
DISPLAY INVISIBLE (-3820 1907);
FORCEPROP 2 LAST CDS_LIB mstr_symbols
J 0
(-3775 1950);
PAINT ORANGE (-3775 1950);
DISPLAY INVISIBLE (-3775 1950);
FORCEPROP 1 LAST SIZE 1B
J 0
(-3700 1900);
DISPLAY 1.170213 (-3700 1900);
PAINT AQUA (-3700 1900);
DISPLAY INVISIBLE (-3700 1900);
FORCEPROP 1 LAST VOLTAGE 0.0V
J 0
(-3820 1907);
DISPLAY 0.340426 (-3820 1907);
PAINT SKYBLUE (-3820 1907);
DISPLAY INVISIBLE (-3820 1907);
FORCEPROP 1 LAST HDL_POWER GND
J 0
(-3775 2100);
DISPLAY 1.170213 (-3775 2100);
PAINT GREEN (-3775 2100);
DISPLAY INVISIBLE (-3775 2100);
FORCEADD CAP_A..1
(-3775 2150);
FORCEPROP 1 LAST PACK_TYPE 0402V
J 0
(-3725 1950);
DISPLAY 0.617021 (-3725 1950);
PAINT SKYBLUE (-3725 1950);
FORCEPROP 1 LAST PART_NUMBER A36096-030
J 0
(-3725 2000);
DISPLAY 0.617021 (-3725 2000);
PAINT BLUE (-3725 2000);
FORCEPROP 1 LASTPIN (-3775 2050) $PN 2
J 0
(-3765 2030);
DISPLAY 0.617021 (-3765 2030);
PAINT ORANGE (-3765 2030);
FORCEPROP 1 LASTPIN (-3775 2250) $PN 1
J 0
(-3765 2230);
DISPLAY 0.617021 (-3765 2230);
PAINT ORANGE (-3765 2230);
FORCEPROP 1 LAST TOLERANCE 10%
J 0
(-3725 2100);
DISPLAY 0.617021 (-3725 2100);
PAINT SKYBLUE (-3725 2100);
FORCEPROP 1 LAST VOLTAGE 16V
J 0
(-3725 2150);
DISPLAY 0.617021 (-3725 2150);
PAINT SKYBLUE (-3725 2150);
FORCEPROP 1 LAST MATERIAL X7R
J 0
(-3725 2050);
DISPLAY 0.617021 (-3725 2050);
PAINT SKYBLUE (-3725 2050);
FORCEPROP 1 LAST VALUE 0.1UF
J 0
(-3725 2200);
DISPLAY 0.617021 (-3725 2200);
PAINT SKYBLUE (-3725 2200);
FORCEPROP 1 LAST LOCATION C9M6
J 0
(-3725 2250);
DISPLAY 0.617021 (-3725 2250);
PAINT AQUA (-3725 2250);
FORCEPROP 2 LAST CDS_LOCATION C9M6
J 0
(-3725 2250);
DISPLAY 0.617021 (-3725 2250);
PAINT AQUA (-3725 2250);
DISPLAY INVISIBLE (-3725 2250);
FORCEPROP 2 LAST CDS_LIB dev_discrete
J 0
(-3775 2150);
PAINT ORANGE (-3775 2150);
DISPLAY INVISIBLE (-3775 2150);
FORCEPROP 1 LAST PATH I67
J 0
(-3725 2300);
DISPLAY 0.978723 (-3725 2300);
PAINT WHITE (-3725 2300);
DISPLAY INVISIBLE (-3725 2300);
FORCEPROP 2 LAST CDS_SEC 1
J 0
(-3725 2300);
PAINT ORANGE (-3725 2300);
DISPLAY INVISIBLE (-3725 2300);
FORCEPROP 0 LAST ROOM P12V_FAN_PWR_SWITCH
J 0
(-3725 2350);
DISPLAY 1.021277 (-3725 2350);
PAINT ORANGE (-3725 2350);
DISPLAY INVISIBLE (-3725 2350);
FORCEPROP 2 LAST SEC_TYPE 0402V
J 0
(-3725 2350);
DISPLAY 1.021277 (-3725 2350);
PAINT ORANGE (-3725 2350);
DISPLAY INVISIBLE (-3725 2350);
FORCEPROP 2 LAST SEC 1
J 0
(-3725 2350);
DISPLAY 0.680851 (-3725 2350);
PAINT MONO (-3725 2350);
DISPLAY INVISIBLE (-3725 2350);
FORCEADD P5V_STBY..1
(-3425 2500);
FORCEPROP 3 LASTPIN (-3425 2450) SIG_NAME P5V_STBY\g
J 0
(-3415 2460);
DISPLAY 0.659574 (-3415 2460);
PAINT MONO (-3415 2460);
DISPLAY INVISIBLE (-3415 2460);
FORCEPROP 1 LAST HDL_POWER P5V_STBY
J 0
(-3725 2375);
DISPLAY 0.872340 (-3725 2375);
PAINT ORANGE (-3725 2375);
DISPLAY INVISIBLE (-3725 2375);
FORCEPROP 1 LAST BODY_TYPE PLUMBING
J 0
(-3470 2457);
DISPLAY 0.340426 (-3470 2457);
PAINT GREEN (-3470 2457);
DISPLAY INVISIBLE (-3470 2457);
FORCEPROP 1 LAST VOLTAGE 5.0V
J 0
(-3470 2457);
DISPLAY 0.340426 (-3470 2457);
PAINT SKYBLUE (-3470 2457);
DISPLAY INVISIBLE (-3470 2457);
FORCEPROP 2 LAST CDS_LIB mstr_symbols
J 0
(-3425 2500);
PAINT ORANGE (-3425 2500);
DISPLAY INVISIBLE (-3425 2500);
FORCEPROP 1 LAST SIZE 1B
J 0
(-3380 2522);
DISPLAY 0.340426 (-3380 2522);
PAINT GREEN (-3380 2522);
DISPLAY INVISIBLE (-3380 2522);
FORCEPROP 1 LAST PATH I68
J 0
(-3380 2502);
DISPLAY 0.340426 (-3380 2502);
PAINT GREEN (-3380 2502);
DISPLAY INVISIBLE (-3380 2502);
FORCEADD SLG55021..1
(-2775 1825);
FORCEPROP 2 LASTPIN (-3075 1775) $PN 3
J 2
(-3085 1785);
DISPLAY 0.617021 (-3085 1785);
PAINT ORANGE (-3085 1785);
FORCEPROP 2 LASTPIN (-3075 1975) $PN 1
J 2
(-3085 1985);
DISPLAY 0.617021 (-3085 1985);
PAINT ORANGE (-3085 1985);
FORCEPROP 2 LASTPIN (-3075 1875) $PN 2
J 2
(-3085 1885);
DISPLAY 0.617021 (-3085 1885);
PAINT ORANGE (-3085 1885);
FORCEPROP 1 LAST PART_NUMBER G56246-001
J 0
(-3025 1525);
DISPLAY 0.617021 (-3025 1525);
PAINT BLUE (-3025 1525);
FORCEPROP 2 LASTPIN (-2475 1675) $PN 4
J 0
(-2465 1685);
DISPLAY 0.617021 (-2465 1685);
PAINT ORANGE (-2465 1685);
FORCEPROP 2 LASTPIN (-2475 1625) $PN 9
J 0
(-2465 1635);
DISPLAY 0.617021 (-2465 1635);
PAINT ORANGE (-2465 1635);
FORCEPROP 2 LASTPIN (-2475 1775) $PN 6
J 0
(-2465 1785);
DISPLAY 0.617021 (-2465 1785);
PAINT ORANGE (-2465 1785);
FORCEPROP 2 LASTPIN (-2475 1975) $PN 8
J 0
(-2465 1985);
DISPLAY 0.617021 (-2465 1985);
PAINT ORANGE (-2465 1985);
FORCEPROP 2 LASTPIN (-2475 1825) $PN 7
J 0
(-2465 1835);
DISPLAY 0.617021 (-2465 1835);
PAINT ORANGE (-2465 1835);
FORCEPROP 2 LASTPIN (-2475 1875) $PN 5
J 0
(-2465 1885);
DISPLAY 0.617021 (-2465 1885);
PAINT ORANGE (-2465 1885);
FORCEPROP 1 LAST MATERIAL IC
J 0
(-3025 2125);
DISPLAY 0.617021 (-3025 2125);
PAINT SKYBLUE (-3025 2125);
FORCEPROP 1 LAST LOCATION EU9M1
J 0
(-3025 2175);
DISPLAY 0.617021 (-3025 2175);
PAINT AQUA (-3025 2175);
FORCEPROP 2 LAST CDS_LIB mstr_vreg
J 0
(-2775 1825);
PAINT ORANGE (-2775 1825);
DISPLAY INVISIBLE (-2775 1825);
FORCEPROP 1 LAST CDS_LMAN_SYM_OUTLINE -250,250,250,-250
J 0
(-2775 1825);
DISPLAY 0.468085 (-2775 1825);
PAINT GREEN (-2775 1825);
DISPLAY INVISIBLE (-2775 1825);
FORCEPROP 0 LAST ROOM P12V_FAN_PWR_SWITCH
J 0
(-3025 2275);
DISPLAY 1.021277 (-3025 2275);
PAINT ORANGE (-3025 2275);
DISPLAY INVISIBLE (-3025 2275);
FORCEPROP 1 LAST PATH I69
J 0
(-2775 2125);
PAINT GREEN (-2775 2125);
DISPLAY INVISIBLE (-2775 2125);
FORCEPROP 2 LAST CDS_LOCATION EU9M1
J 0
(-3025 2175);
DISPLAY 0.617021 (-3025 2175);
PAINT AQUA (-3025 2175);
DISPLAY INVISIBLE (-3025 2175);
FORCEPROP 2 LAST SEC 1
J 0
(-3025 2225);
DISPLAY 0.680851 (-3025 2225);
PAINT MONO (-3025 2225);
DISPLAY INVISIBLE (-3025 2225);
FORCEPROP 2 LAST SEC_TYPE SM
J 0
(-3025 2225);
DISPLAY 1.021277 (-3025 2225);
PAINT ORANGE (-3025 2225);
DISPLAY INVISIBLE (-3025 2225);
FORCEPROP 1 LAST PACK_TYPE SM
J 0
(-3025 2225);
PAINT SKYBLUE (-3025 2225);
DISPLAY INVISIBLE (-3025 2225);
FORCEADD P3V3..1
(-5125 3675);
FORCEPROP 3 LASTPIN (-5125 3625) SIG_NAME P3V3\g
J 0
(-5115 3635);
DISPLAY 0.659574 (-5115 3635);
PAINT MONO (-5115 3635);
DISPLAY INVISIBLE (-5115 3635);
FORCEPROP 1 LAST HDL_POWER P3V3
J 0
(-5450 3550);
DISPLAY 0.872340 (-5450 3550);
PAINT ORANGE (-5450 3550);
DISPLAY INVISIBLE (-5450 3550);
FORCEPROP 1 LAST BODY_TYPE PLUMBING
J 0
(-5170 3632);
DISPLAY 0.340426 (-5170 3632);
PAINT GREEN (-5170 3632);
DISPLAY INVISIBLE (-5170 3632);
FORCEPROP 2 LAST CDS_LIB mstr_symbols
J 0
(-5125 3675);
PAINT ORANGE (-5125 3675);
DISPLAY INVISIBLE (-5125 3675);
FORCEPROP 1 LAST PATH I7
J 0
(-5080 3677);
DISPLAY 0.340426 (-5080 3677);
PAINT GREEN (-5080 3677);
DISPLAY INVISIBLE (-5080 3677);
FORCEPROP 1 LAST SIZE 1B
J 0
(-5080 3697);
DISPLAY 0.340426 (-5080 3697);
PAINT GREEN (-5080 3697);
DISPLAY INVISIBLE (-5080 3697);
FORCEPROP 1 LAST VOLTAGE +3.3V
J 0
(-5025 3825);
DISPLAY 1.021277 (-5025 3825);
PAINT SKYBLUE (-5025 3825);
DISPLAY INVISIBLE (-5025 3825);
FORCEADD GND..1
(-2250 1450);
FORCEPROP 3 LASTPIN (-2250 1500) SIG_NAME GND\g
J 0
(-2240 1510);
DISPLAY 0.659574 (-2240 1510);
PAINT MONO (-2240 1510);
DISPLAY INVISIBLE (-2240 1510);
FORCEPROP 1 LAST PATH I70
J 0
(-2175 1450);
DISPLAY 0.872340 (-2175 1450);
PAINT AQUA (-2175 1450);
DISPLAY INVISIBLE (-2175 1450);
FORCEPROP 1 LAST BODY_TYPE PLUMBING
J 0
(-2295 1407);
DISPLAY 0.340426 (-2295 1407);
PAINT GREEN (-2295 1407);
DISPLAY INVISIBLE (-2295 1407);
FORCEPROP 2 LAST CDS_LIB mstr_symbols
J 0
(-2250 1450);
PAINT ORANGE (-2250 1450);
DISPLAY INVISIBLE (-2250 1450);
FORCEPROP 1 LAST SIZE 1B
J 0
(-2175 1400);
DISPLAY 1.170213 (-2175 1400);
PAINT AQUA (-2175 1400);
DISPLAY INVISIBLE (-2175 1400);
FORCEPROP 1 LAST VOLTAGE 0.0V
J 0
(-2295 1407);
DISPLAY 0.340426 (-2295 1407);
PAINT SKYBLUE (-2295 1407);
DISPLAY INVISIBLE (-2295 1407);
FORCEPROP 1 LAST HDL_POWER GND
J 0
(-2250 1600);
DISPLAY 1.170213 (-2250 1600);
PAINT GREEN (-2250 1600);
DISPLAY INVISIBLE (-2250 1600);
FORCEADD P12V_STBY..1
(-1375 2550);
FORCEPROP 3 LASTPIN (-1375 2500) SIG_NAME P12V_STBY\g
J 0
(-1365 2510);
DISPLAY 0.659574 (-1365 2510);
PAINT MONO (-1365 2510);
DISPLAY INVISIBLE (-1365 2510);
FORCEPROP 1 LAST HDL_POWER P12V_STBY
J 0
(-1675 2425);
DISPLAY 0.872340 (-1675 2425);
PAINT ORANGE (-1675 2425);
DISPLAY INVISIBLE (-1675 2425);
FORCEPROP 1 LAST VOLTAGE 12.0V
J 0
(-1420 2507);
DISPLAY 0.340426 (-1420 2507);
PAINT SKYBLUE (-1420 2507);
DISPLAY INVISIBLE (-1420 2507);
FORCEPROP 1 LAST BODY_TYPE PLUMBING
J 0
(-1420 2507);
DISPLAY 0.340426 (-1420 2507);
PAINT GREEN (-1420 2507);
DISPLAY INVISIBLE (-1420 2507);
FORCEPROP 1 LAST PATH I73
J 0
(-1330 2552);
DISPLAY 0.340426 (-1330 2552);
PAINT GREEN (-1330 2552);
DISPLAY INVISIBLE (-1330 2552);
FORCEPROP 2 LAST CDS_LIB mstr_symbols
J 0
(-1375 2550);
PAINT ORANGE (-1375 2550);
DISPLAY INVISIBLE (-1375 2550);
FORCEPROP 1 LAST SIZE 1B
J 0
(-1330 2572);
DISPLAY 0.340426 (-1330 2572);
PAINT GREEN (-1330 2572);
DISPLAY INVISIBLE (-1330 2572);
FORCEADD CAP..1
(-1150 2225);
FORCEPROP 1 LASTPIN (-1150 2325) $PN 1
J 0
(-1140 2305);
DISPLAY 0.617021 (-1140 2305);
PAINT ORANGE (-1140 2305);
FORCEPROP 1 LAST VOLTAGE 16V
J 0
(-1100 2225);
DISPLAY 0.617021 (-1100 2225);
PAINT SKYBLUE (-1100 2225);
FORCEPROP 1 LAST TOLERANCE 10%
J 0
(-1100 2175);
DISPLAY 0.617021 (-1100 2175);
PAINT SKYBLUE (-1100 2175);
FORCEPROP 1 LAST VALUE 10UF
J 0
(-1100 2275);
DISPLAY 0.617021 (-1100 2275);
PAINT SKYBLUE (-1100 2275);
FORCEPROP 1 LAST PACK_TYPE 0805
J 0
(-1100 2025);
DISPLAY 0.617021 (-1100 2025);
PAINT SKYBLUE (-1100 2025);
FORCEPROP 1 LAST LOCATION C9M10
J 0
(-1100 2325);
DISPLAY 0.617021 (-1100 2325);
PAINT AQUA (-1100 2325);
FORCEPROP 1 LASTPIN (-1150 2125) $PN 2
J 0
(-1140 2105);
DISPLAY 0.617021 (-1140 2105);
PAINT ORANGE (-1140 2105);
FORCEPROP 1 LAST MATERIAL X6S
J 0
(-1100 2125);
DISPLAY 0.617021 (-1100 2125);
PAINT SKYBLUE (-1100 2125);
FORCEPROP 1 LAST PART_NUMBER C95333-007
J 0
(-1100 2075);
DISPLAY 0.617021 (-1100 2075);
PAINT BLUE (-1100 2075);
FORCEPROP 2 LAST CDS_LIB mstr_discrete
J 0
(-1150 2225);
PAINT ORANGE (-1150 2225);
DISPLAY INVISIBLE (-1150 2225);
FORCEPROP 2 LAST SEC_TYPE 0805
J 0
(-1100 2425);
DISPLAY 1.021277 (-1100 2425);
PAINT ORANGE (-1100 2425);
DISPLAY INVISIBLE (-1100 2425);
FORCEPROP 2 LAST SEC 1
J 0
(-1100 2425);
DISPLAY 0.680851 (-1100 2425);
PAINT MONO (-1100 2425);
DISPLAY INVISIBLE (-1100 2425);
FORCEPROP 2 LAST CDS_LOCATION C9M10
J 0
(-1100 2325);
DISPLAY 0.617021 (-1100 2325);
PAINT AQUA (-1100 2325);
DISPLAY INVISIBLE (-1100 2325);
FORCEPROP 1 LAST PATH I74
J 0
(-1100 2375);
DISPLAY 0.978723 (-1100 2375);
PAINT WHITE (-1100 2375);
DISPLAY INVISIBLE (-1100 2375);
FORCEPROP 2 LAST ROOM P12V_FAN_PWR_SWITCH
J 0
(-1100 2375);
DISPLAY 1.361702 (-1100 2375);
PAINT ORANGE (-1100 2375);
DISPLAY INVISIBLE (-1100 2375);
FORCEADD GND..1
(-850 1900);
FORCEPROP 3 LASTPIN (-850 1950) SIG_NAME GND\g
J 0
(-840 1960);
DISPLAY 0.659574 (-840 1960);
PAINT MONO (-840 1960);
DISPLAY INVISIBLE (-840 1960);
FORCEPROP 1 LAST VOLTAGE 0.0V
J 0
(-895 1857);
DISPLAY 0.340426 (-895 1857);
PAINT SKYBLUE (-895 1857);
DISPLAY INVISIBLE (-895 1857);
FORCEPROP 2 LAST CDS_LIB mstr_symbols
J 0
(-850 1900);
PAINT ORANGE (-850 1900);
DISPLAY INVISIBLE (-850 1900);
FORCEPROP 1 LAST SIZE 1B
J 0
(-775 1850);
DISPLAY 1.170213 (-775 1850);
PAINT AQUA (-775 1850);
DISPLAY INVISIBLE (-775 1850);
FORCEPROP 1 LAST BODY_TYPE PLUMBING
J 0
(-895 1857);
DISPLAY 0.340426 (-895 1857);
PAINT GREEN (-895 1857);
DISPLAY INVISIBLE (-895 1857);
FORCEPROP 1 LAST PATH I75
J 0
(-775 1900);
DISPLAY 0.872340 (-775 1900);
PAINT AQUA (-775 1900);
DISPLAY INVISIBLE (-775 1900);
FORCEPROP 1 LAST HDL_POWER GND
J 0
(-850 2050);
DISPLAY 1.170213 (-850 2050);
PAINT GREEN (-850 2050);
DISPLAY INVISIBLE (-850 2050);
FORCEADD CAP_A..1
(-825 2225);
FORCEPROP 1 LAST PACK_TYPE 0402V
J 0
(-775 2025);
DISPLAY 0.617021 (-775 2025);
PAINT SKYBLUE (-775 2025);
FORCEPROP 1 LASTPIN (-825 2125) $PN 2
J 0
(-815 2105);
DISPLAY 0.617021 (-815 2105);
PAINT ORANGE (-815 2105);
FORCEPROP 1 LASTPIN (-825 2325) $PN 1
J 0
(-815 2305);
DISPLAY 0.617021 (-815 2305);
PAINT ORANGE (-815 2305);
FORCEPROP 1 LAST LOCATION C9M9
J 0
(-775 2325);
DISPLAY 0.617021 (-775 2325);
PAINT AQUA (-775 2325);
FORCEPROP 1 LAST PART_NUMBER A36096-030
J 0
(-775 2075);
DISPLAY 0.617021 (-775 2075);
PAINT BLUE (-775 2075);
FORCEPROP 1 LAST MATERIAL X7R
J 0
(-775 2125);
DISPLAY 0.617021 (-775 2125);
PAINT SKYBLUE (-775 2125);
FORCEPROP 1 LAST TOLERANCE 10%
J 0
(-775 2175);
DISPLAY 0.617021 (-775 2175);
PAINT SKYBLUE (-775 2175);
FORCEPROP 1 LAST VOLTAGE 16V
J 0
(-775 2225);
DISPLAY 0.617021 (-775 2225);
PAINT SKYBLUE (-775 2225);
FORCEPROP 1 LAST VALUE 0.1UF
J 0
(-775 2275);
DISPLAY 0.617021 (-775 2275);
PAINT SKYBLUE (-775 2275);
FORCEPROP 2 LAST CDS_LIB dev_discrete
J 0
(-825 2225);
PAINT ORANGE (-825 2225);
DISPLAY INVISIBLE (-825 2225);
FORCEPROP 2 LAST SEC 1
J 0
(-775 2425);
DISPLAY 0.680851 (-775 2425);
PAINT MONO (-775 2425);
DISPLAY INVISIBLE (-775 2425);
FORCEPROP 2 LAST SEC_TYPE 0402V
J 0
(-775 2425);
DISPLAY 1.021277 (-775 2425);
PAINT ORANGE (-775 2425);
DISPLAY INVISIBLE (-775 2425);
FORCEPROP 2 LAST CDS_SEC 1
J 0
(-775 2375);
PAINT ORANGE (-775 2375);
DISPLAY INVISIBLE (-775 2375);
FORCEPROP 2 LAST CDS_LOCATION C9M9
J 0
(-775 2325);
DISPLAY 0.617021 (-775 2325);
PAINT AQUA (-775 2325);
DISPLAY INVISIBLE (-775 2325);
FORCEPROP 1 LAST PATH I76
J 0
(-775 2375);
DISPLAY 0.978723 (-775 2375);
PAINT WHITE (-775 2375);
DISPLAY INVISIBLE (-775 2375);
FORCEPROP 0 LAST ROOM P12V_FAN_PWR_SWITCH
J 0
(-775 2425);
DISPLAY 1.021277 (-775 2425);
PAINT ORANGE (-775 2425);
DISPLAY INVISIBLE (-775 2425);
FORCEPROP 0 LAST BOM_COST PWR_SWITCH
J 0
(-775 2525);
DISPLAY 1.021277 (-775 2525);
PAINT ORANGE (-775 2525);
DISPLAY INVISIBLE (-775 2525);
FORCEADD P12V_FAN..1
(-725 1600);
FORCEPROP 3 LASTPIN (-725 1550) SIG_NAME P12V_FAN\g
J 0
(-715 1560);
DISPLAY 0.659574 (-715 1560);
PAINT MONO (-715 1560);
DISPLAY INVISIBLE (-715 1560);
FORCEPROP 1 LAST VOLTAGE 12.0V
J 0
(-770 1557);
DISPLAY 0.340426 (-770 1557);
PAINT SKYBLUE (-770 1557);
DISPLAY INVISIBLE (-770 1557);
FORCEPROP 1 LAST BODY_TYPE PLUMBING
J 0
(-770 1557);
DISPLAY 0.340426 (-770 1557);
PAINT GREEN (-770 1557);
DISPLAY INVISIBLE (-770 1557);
FORCEPROP 2 LAST CDS_LIB mstr_symbols
J 0
(-725 1600);
PAINT ORANGE (-725 1600);
DISPLAY INVISIBLE (-725 1600);
FORCEPROP 1 LAST PATH I77
J 0
(-675 1625);
DISPLAY 0.872340 (-675 1625);
PAINT AQUA (-675 1625);
DISPLAY INVISIBLE (-675 1625);
FORCEPROP 1 LAST HDL_POWER P12V_FAN
J 1
(-725 1650);
DISPLAY 0.872340 (-725 1650);
PAINT GREEN (-725 1650);
DISPLAY INVISIBLE (-725 1650);
FORCEADD RES..2
(-6925 3050);
FORCEPROP 1 LAST WATTAGE 1/16W
J 0
(-6885 3025);
DISPLAY 0.617021 (-6885 3025);
PAINT SKYBLUE (-6885 3025);
FORCEPROP 1 LAST MATERIAL EMPTY
J 0
(-6885 2975);
DISPLAY 0.617021 (-6885 2975);
PAINT RED (-6885 2975);
FORCEPROP 1 LAST PACK_TYPE 0402
J 0
(-6885 2875);
DISPLAY 0.617021 (-6885 2875);
PAINT SKYBLUE (-6885 2875);
FORCEPROP 1 LAST PART_NUMBER G21796-072
J 0
(-6885 2925);
DISPLAY 0.617021 (-6885 2925);
PAINT BLUE (-6885 2925);
FORCEPROP 1 LAST TOLERANCE 1%
J 0
(-6880 3075);
DISPLAY 0.617021 (-6880 3075);
PAINT SKYBLUE (-6880 3075);
FORCEPROP 1 LAST LOCATION R8E12
J 0
(-6880 3175);
DISPLAY 0.617021 (-6880 3175);
PAINT AQUA (-6880 3175);
FORCEPROP 1 LAST VALUE 4.75K
J 0
(-6880 3125);
DISPLAY 0.617021 (-6880 3125);
PAINT SKYBLUE (-6880 3125);
FORCEPROP 1 LASTPIN (-6925 2950) $PN 2
J 0
(-6920 2960);
DISPLAY 0.787234 (-6920 2960);
PAINT ORANGE (-6920 2960);
DISPLAY INVISIBLE (-6920 2960);
FORCEPROP 2 LAST CDS_LIB mstr_discrete
J 0
(-6925 3050);
PAINT MONO (-6925 3050);
DISPLAY INVISIBLE (-6925 3050);
FORCEPROP 1 LASTPIN (-6925 3150) $PN 1
J 0
(-6920 3112);
DISPLAY 0.787234 (-6920 3112);
PAINT ORANGE (-6920 3112);
DISPLAY INVISIBLE (-6920 3112);
FORCEPROP 0 LAST ROOM IO_SLOT
J 0
(-6875 3275);
DISPLAY 1.021277 (-6875 3275);
PAINT ORANGE (-6875 3275);
DISPLAY INVISIBLE (-6875 3275);
FORCEPROP 2 LAST CDS_LOCATION R8E12
J 0
(-6880 3175);
DISPLAY 0.617021 (-6880 3175);
PAINT AQUA (-6880 3175);
DISPLAY INVISIBLE (-6880 3175);
FORCEPROP 2 LAST $SEC 1
J 0
(-6875 3275);
PAINT MONO (-6875 3275);
DISPLAY INVISIBLE (-6875 3275);
FORCEPROP 2 LAST CDS_SEC 1
J 0
(-6875 3275);
PAINT MONO (-6875 3275);
DISPLAY INVISIBLE (-6875 3275);
FORCEPROP 1 LAST PATH I78
J 0
(-6875 3225);
DISPLAY 0.978723 (-6875 3225);
PAINT WHITE (-6875 3225);
DISPLAY INVISIBLE (-6875 3225);
FORCEPROP 0 LAST BOM_COST IO_SLOT
J 0
(-6875 3375);
DISPLAY 1.021277 (-6875 3375);
PAINT ORANGE (-6875 3375);
DISPLAY INVISIBLE (-6875 3375);
FORCEADD P3V3_STBY..1
(-6925 3275);
FORCEPROP 3 LASTPIN (-6925 3225) SIG_NAME P3V3_STBY\g
J 0
(-6915 3235);
DISPLAY 0.659574 (-6915 3235);
PAINT MONO (-6915 3235);
DISPLAY INVISIBLE (-6915 3235);
FORCEPROP 1 LAST HDL_POWER P3V3_STBY
J 0
(-7225 3150);
DISPLAY 0.872340 (-7225 3150);
PAINT ORANGE (-7225 3150);
DISPLAY INVISIBLE (-7225 3150);
FORCEPROP 1 LAST BODY_TYPE PLUMBING
J 0
(-6970 3232);
DISPLAY 0.340426 (-6970 3232);
PAINT GREEN (-6970 3232);
DISPLAY INVISIBLE (-6970 3232);
FORCEPROP 2 LAST CDS_LIB mstr_symbols
J 0
(-6925 3275);
PAINT MONO (-6925 3275);
DISPLAY INVISIBLE (-6925 3275);
FORCEPROP 1 LAST VOLTAGE 3.3V
J 0
(-6970 3232);
DISPLAY 0.340426 (-6970 3232);
PAINT SKYBLUE (-6970 3232);
DISPLAY INVISIBLE (-6970 3232);
FORCEPROP 1 LAST PATH I79
J 0
(-6880 3277);
DISPLAY 0.340426 (-6880 3277);
PAINT GREEN (-6880 3277);
DISPLAY INVISIBLE (-6880 3277);
FORCEPROP 1 LAST SIZE 1B
J 0
(-6880 3297);
DISPLAY 0.340426 (-6880 3297);
PAINT GREEN (-6880 3297);
DISPLAY INVISIBLE (-6880 3297);
FORCEADD RES..2
(-6850 2625);
FORCEPROP 1 LASTPIN (-6850 2525) $PN 2
J 0
(-6845 2535);
DISPLAY 0.617021 (-6845 2535);
PAINT ORANGE (-6845 2535);
FORCEPROP 1 LAST MATERIAL CHIP
J 0
(-6810 2550);
DISPLAY 0.617021 (-6810 2550);
PAINT SKYBLUE (-6810 2550);
FORCEPROP 1 LASTPIN (-6850 2725) $PN 1
J 0
(-6845 2687);
DISPLAY 0.617021 (-6845 2687);
PAINT ORANGE (-6845 2687);
FORCEPROP 1 LAST LOCATION R8B4
J 0
(-6805 2750);
DISPLAY 0.617021 (-6805 2750);
PAINT AQUA (-6805 2750);
FORCEPROP 1 LAST TOLERANCE 1%
J 0
(-6805 2650);
DISPLAY 0.617021 (-6805 2650);
PAINT SKYBLUE (-6805 2650);
FORCEPROP 1 LAST WATTAGE 1/16W
J 0
(-6810 2600);
DISPLAY 0.617021 (-6810 2600);
PAINT SKYBLUE (-6810 2600);
FORCEPROP 1 LAST VALUE 100.0K
J 0
(-6805 2700);
DISPLAY 0.617021 (-6805 2700);
PAINT SKYBLUE (-6805 2700);
FORCEPROP 1 LAST PART_NUMBER G21796-010
J 0
(-6810 2500);
DISPLAY 0.617021 (-6810 2500);
PAINT BLUE (-6810 2500);
FORCEPROP 1 LAST PACK_TYPE 0402
J 0
(-6810 2450);
DISPLAY 0.617021 (-6810 2450);
PAINT SKYBLUE (-6810 2450);
FORCEPROP 2 LAST CDS_LIB mstr_discrete
J 0
(-6850 2625);
PAINT ORANGE (-6850 2625);
DISPLAY INVISIBLE (-6850 2625);
FORCEPROP 2 LAST CDS_LOCATION R8B4
J 0
(-6805 2750);
DISPLAY 0.617021 (-6805 2750);
PAINT AQUA (-6805 2750);
DISPLAY INVISIBLE (-6805 2750);
FORCEPROP 2 LAST ROOM HOT_SWAP
J 0
(-6800 2800);
PAINT MONO (-6800 2800);
DISPLAY INVISIBLE (-6800 2800);
FORCEPROP 1 LAST PATH I83
J 0
(-6800 2800);
DISPLAY 0.978723 (-6800 2800);
PAINT WHITE (-6800 2800);
DISPLAY INVISIBLE (-6800 2800);
FORCEPROP 2 LAST SEC_TYPE 0402
J 0
(-6800 2850);
DISPLAY 1.021277 (-6800 2850);
PAINT ORANGE (-6800 2850);
DISPLAY INVISIBLE (-6800 2850);
FORCEPROP 2 LAST SEC 1
J 0
(-6800 2850);
DISPLAY 0.680851 (-6800 2850);
PAINT MONO (-6800 2850);
DISPLAY INVISIBLE (-6800 2850);
FORCEADD GND..1
(-6850 2425);
FORCEPROP 3 LASTPIN (-6850 2475) SIG_NAME GND\g
J 0
(-6840 2485);
DISPLAY 0.659574 (-6840 2485);
PAINT MONO (-6840 2485);
DISPLAY INVISIBLE (-6840 2485);
FORCEPROP 1 LAST VOLTAGE 0.0V
J 0
(-6895 2382);
DISPLAY 0.340426 (-6895 2382);
PAINT SKYBLUE (-6895 2382);
DISPLAY INVISIBLE (-6895 2382);
FORCEPROP 2 LAST CDS_LIB mstr_symbols
J 0
(-6850 2425);
PAINT ORANGE (-6850 2425);
DISPLAY INVISIBLE (-6850 2425);
FORCEPROP 1 LAST BODY_TYPE PLUMBING
J 0
(-6895 2382);
DISPLAY 0.340426 (-6895 2382);
PAINT GREEN (-6895 2382);
DISPLAY INVISIBLE (-6895 2382);
FORCEPROP 1 LAST SIZE 1B
J 0
(-6775 2375);
DISPLAY 1.170213 (-6775 2375);
PAINT AQUA (-6775 2375);
DISPLAY INVISIBLE (-6775 2375);
FORCEPROP 1 LAST PATH I84
J 0
(-6775 2425);
DISPLAY 0.872340 (-6775 2425);
PAINT AQUA (-6775 2425);
DISPLAY INVISIBLE (-6775 2425);
FORCEPROP 1 LAST HDL_POWER GND
J 0
(-6850 2575);
DISPLAY 1.170213 (-6850 2575);
PAINT GREEN (-6850 2575);
DISPLAY INVISIBLE (-6850 2575);
FORCEADD MOSFET_N..3
R 2
(-5650 3900);
FORCEPROP 1 LASTPIN (-5650 3700) $PN 1
J 2
(-5662 3695);
DISPLAY 0.617021 (-5662 3695);
PAINT WHITE (-5662 3695);
FORCEPROP 1 LASTPIN (-5850 4000) $PN 4
J 2
(-5847 4015);
DISPLAY 0.617021 (-5847 4015);
PAINT WHITE (-5847 4015);
FORCEPROP 1 LAST MATERIAL NFET
J 0
(-5475 3850);
DISPLAY 0.617021 (-5475 3850);
PAINT SKYBLUE (-5475 3850);
FORCEPROP 1 LAST LOCATION Q8G1
J 0
(-5475 3950);
DISPLAY 0.617021 (-5475 3950);
PAINT AQUA (-5475 3950);
FORCEPROP 1 LASTPIN (-5650 4100) $PN 5
J 2
(-5662 4075);
DISPLAY 0.617021 (-5662 4075);
PAINT WHITE (-5662 4075);
FORCEPROP 1 LAST VALUE BSZ019N03LS
J 0
(-5475 3900);
DISPLAY 0.617021 (-5475 3900);
PAINT SKYBLUE (-5475 3900);
FORCEPROP 1 LAST PART_NUMBER G26762-001
J 0
(-5475 3750);
DISPLAY 0.617021 (-5475 3750);
PAINT BLUE (-5475 3750);
FORCEPROP 2 LAST CDS_LIB mstr_discrete
J 0
(-5650 3900);
PAINT ORANGE (-5650 3900);
DISPLAY INVISIBLE (-5650 3900);
FORCEPROP 1 LAST PACK_TYPE LCC3
J 0
(-5475 3800);
DISPLAY 0.978723 (-5475 3800);
PAINT SKYBLUE (-5475 3800);
DISPLAY INVISIBLE (-5475 3800);
FORCEPROP 2 LAST SEC_TYPE LCC3
J 0
(-5475 4050);
DISPLAY 1.021277 (-5475 4050);
PAINT ORANGE (-5475 4050);
DISPLAY INVISIBLE (-5475 4050);
FORCEPROP 2 LAST SEC 1
J 0
(-5475 4050);
DISPLAY 0.680851 (-5475 4050);
PAINT MONO (-5475 4050);
DISPLAY INVISIBLE (-5475 4050);
FORCEPROP 1 LAST PATH I85
J 0
(-5475 4000);
DISPLAY 0.978723 (-5475 4000);
PAINT BLUE (-5475 4000);
DISPLAY INVISIBLE (-5475 4000);
FORCEPROP 2 LAST CDS_LOCATION Q8G1
J 0
(-5475 3950);
DISPLAY 0.617021 (-5475 3950);
PAINT AQUA (-5475 3950);
DISPLAY INVISIBLE (-5475 3950);
FORCEADD MOSFET_N..3
R 2
(-1375 1850);
FORCEPROP 1 LASTPIN (-1575 1950) $PN 4
J 2
(-1572 1965);
DISPLAY 0.617021 (-1572 1965);
PAINT WHITE (-1572 1965);
FORCEPROP 1 LASTPIN (-1375 1650) $PN 1
J 2
(-1387 1645);
DISPLAY 0.617021 (-1387 1645);
PAINT WHITE (-1387 1645);
FORCEPROP 1 LAST MATERIAL NFET
J 0
(-1200 1800);
DISPLAY 0.617021 (-1200 1800);
PAINT SKYBLUE (-1200 1800);
FORCEPROP 1 LAST LOCATION Q1B1
J 0
(-1200 1900);
DISPLAY 0.617021 (-1200 1900);
PAINT AQUA (-1200 1900);
FORCEPROP 1 LAST VALUE BSZ019N03LS
J 0
(-1200 1850);
DISPLAY 0.617021 (-1200 1850);
PAINT SKYBLUE (-1200 1850);
FORCEPROP 1 LAST PART_NUMBER G26762-001
J 0
(-1200 1700);
DISPLAY 0.617021 (-1200 1700);
PAINT BLUE (-1200 1700);
FORCEPROP 1 LASTPIN (-1375 2050) $PN 5
J 2
(-1387 2025);
DISPLAY 0.617021 (-1387 2025);
PAINT WHITE (-1387 2025);
FORCEPROP 2 LAST CDS_LIB mstr_discrete
J 0
(-1375 1850);
PAINT ORANGE (-1375 1850);
DISPLAY INVISIBLE (-1375 1850);
FORCEPROP 1 LAST PATH I86
J 0
(-1200 1950);
DISPLAY 0.978723 (-1200 1950);
PAINT BLUE (-1200 1950);
DISPLAY INVISIBLE (-1200 1950);
FORCEPROP 2 LAST CDS_LOCATION Q1B1
J 0
(-1200 1900);
DISPLAY 0.617021 (-1200 1900);
PAINT AQUA (-1200 1900);
DISPLAY INVISIBLE (-1200 1900);
FORCEPROP 2 LAST SEC 1
J 0
(-1200 2000);
DISPLAY 0.680851 (-1200 2000);
PAINT MONO (-1200 2000);
DISPLAY INVISIBLE (-1200 2000);
FORCEPROP 2 LAST SEC_TYPE LCC3
J 0
(-1200 2000);
DISPLAY 1.021277 (-1200 2000);
PAINT ORANGE (-1200 2000);
DISPLAY INVISIBLE (-1200 2000);
FORCEPROP 1 LAST PACK_TYPE LCC3
J 0
(-1200 1750);
DISPLAY 0.978723 (-1200 1750);
PAINT SKYBLUE (-1200 1750);
DISPLAY INVISIBLE (-1200 1750);
FORCEADD MOSFET_N..3
R 2
(-1600 3850);
FORCEPROP 1 LASTPIN (-1800 3950) $PN 4
J 2
(-1797 3965);
DISPLAY 0.617021 (-1797 3965);
PAINT WHITE (-1797 3965);
FORCEPROP 1 LASTPIN (-1600 4050) $PN 5
J 2
(-1612 4025);
DISPLAY 0.617021 (-1612 4025);
PAINT WHITE (-1612 4025);
FORCEPROP 1 LAST LOCATION Q8B1
J 0
(-1425 3900);
DISPLAY 0.617021 (-1425 3900);
PAINT AQUA (-1425 3900);
FORCEPROP 1 LASTPIN (-1600 3650) $PN 1
J 2
(-1612 3645);
DISPLAY 0.617021 (-1612 3645);
PAINT WHITE (-1612 3645);
FORCEPROP 1 LAST PART_NUMBER G26762-001
J 0
(-1425 3700);
DISPLAY 0.617021 (-1425 3700);
PAINT BLUE (-1425 3700);
FORCEPROP 1 LAST MATERIAL NFET
J 0
(-1425 3800);
DISPLAY 0.617021 (-1425 3800);
PAINT SKYBLUE (-1425 3800);
FORCEPROP 1 LAST VALUE BSZ019N03LS
J 0
(-1425 3850);
DISPLAY 0.617021 (-1425 3850);
PAINT SKYBLUE (-1425 3850);
FORCEPROP 2 LAST CDS_LIB mstr_discrete
J 0
(-1600 3850);
PAINT ORANGE (-1600 3850);
DISPLAY INVISIBLE (-1600 3850);
FORCEPROP 1 LAST PACK_TYPE LCC3
J 0
(-1425 3750);
DISPLAY 0.978723 (-1425 3750);
PAINT SKYBLUE (-1425 3750);
DISPLAY INVISIBLE (-1425 3750);
FORCEPROP 2 LAST CDS_LOCATION Q8B1
J 0
(-1425 3900);
DISPLAY 0.617021 (-1425 3900);
PAINT AQUA (-1425 3900);
DISPLAY INVISIBLE (-1425 3900);
FORCEPROP 2 LAST SEC 1
J 0
(-1425 4000);
DISPLAY 0.680851 (-1425 4000);
PAINT MONO (-1425 4000);
DISPLAY INVISIBLE (-1425 4000);
FORCEPROP 2 LAST SEC_TYPE LCC3
J 0
(-1425 4000);
DISPLAY 1.021277 (-1425 4000);
PAINT ORANGE (-1425 4000);
DISPLAY INVISIBLE (-1425 4000);
FORCEPROP 1 LAST PATH I87
J 0
(-1425 3950);
DISPLAY 0.978723 (-1425 3950);
PAINT BLUE (-1425 3950);
DISPLAY INVISIBLE (-1425 3950);
FORCEADD MOSFET_N..3
R 2
(-5325 1850);
FORCEPROP 1 LASTPIN (-5525 1950) $PN 4
J 2
(-5522 1965);
DISPLAY 0.617021 (-5522 1965);
PAINT WHITE (-5522 1965);
FORCEPROP 1 LASTPIN (-5325 1650) $PN 1
J 2
(-5337 1645);
DISPLAY 0.617021 (-5337 1645);
PAINT WHITE (-5337 1645);
FORCEPROP 1 LAST MATERIAL NFET
J 0
(-5150 1800);
DISPLAY 0.617021 (-5150 1800);
PAINT SKYBLUE (-5150 1800);
FORCEPROP 1 LAST PART_NUMBER G26762-001
J 0
(-5150 1700);
DISPLAY 0.617021 (-5150 1700);
PAINT BLUE (-5150 1700);
FORCEPROP 1 LASTPIN (-5325 2050) $PN 5
J 2
(-5337 2025);
DISPLAY 0.617021 (-5337 2025);
PAINT WHITE (-5337 2025);
FORCEPROP 1 LAST LOCATION Q7E7
J 0
(-5150 1900);
DISPLAY 0.617021 (-5150 1900);
PAINT AQUA (-5150 1900);
FORCEPROP 1 LAST VALUE BSZ019N03LS
J 0
(-5150 1850);
DISPLAY 0.617021 (-5150 1850);
PAINT SKYBLUE (-5150 1850);
FORCEPROP 1 LAST PACK_TYPE LCC3
J 0
(-5150 1750);
DISPLAY 0.978723 (-5150 1750);
PAINT SKYBLUE (-5150 1750);
DISPLAY INVISIBLE (-5150 1750);
FORCEPROP 2 LAST CDS_LIB mstr_discrete
J 0
(-5325 1850);
PAINT ORANGE (-5325 1850);
DISPLAY INVISIBLE (-5325 1850);
FORCEPROP 1 LAST PATH I88
J 0
(-5150 1950);
DISPLAY 0.978723 (-5150 1950);
PAINT BLUE (-5150 1950);
DISPLAY INVISIBLE (-5150 1950);
FORCEPROP 2 LAST CDS_LOCATION Q7E7
J 0
(-5150 1900);
DISPLAY 0.617021 (-5150 1900);
PAINT AQUA (-5150 1900);
DISPLAY INVISIBLE (-5150 1900);
FORCEPROP 2 LAST SEC 1
J 0
(-5150 2000);
DISPLAY 0.680851 (-5150 2000);
PAINT MONO (-5150 2000);
DISPLAY INVISIBLE (-5150 2000);
FORCEPROP 2 LAST SEC_TYPE LCC3
J 0
(-5150 2000);
DISPLAY 1.021277 (-5150 2000);
PAINT ORANGE (-5150 2000);
DISPLAY INVISIBLE (-5150 2000);
FORCEADD P5V_STBY..1
(-3950 4350);
FORCEPROP 3 LASTPIN (-3950 4300) SIG_NAME P5V_STBY\g
J 0
(-3940 4310);
DISPLAY 0.659574 (-3940 4310);
PAINT MONO (-3940 4310);
DISPLAY INVISIBLE (-3940 4310);
FORCEPROP 1 LAST HDL_POWER P5V_STBY
J 0
(-4250 4225);
DISPLAY 0.872340 (-4250 4225);
PAINT ORANGE (-4250 4225);
DISPLAY INVISIBLE (-4250 4225);
FORCEPROP 1 LAST BODY_TYPE PLUMBING
J 0
(-3995 4307);
DISPLAY 0.340426 (-3995 4307);
PAINT GREEN (-3995 4307);
DISPLAY INVISIBLE (-3995 4307);
FORCEPROP 1 LAST VOLTAGE 5.0V
J 0
(-3995 4307);
DISPLAY 0.340426 (-3995 4307);
PAINT SKYBLUE (-3995 4307);
DISPLAY INVISIBLE (-3995 4307);
FORCEPROP 2 LAST CDS_LIB mstr_symbols
J 0
(-3950 4350);
PAINT ORANGE (-3950 4350);
DISPLAY INVISIBLE (-3950 4350);
FORCEPROP 1 LAST PATH I9
J 0
(-3905 4352);
DISPLAY 0.340426 (-3905 4352);
PAINT GREEN (-3905 4352);
DISPLAY INVISIBLE (-3905 4352);
FORCEPROP 1 LAST SIZE 1B
J 0
(-3905 4372);
DISPLAY 0.340426 (-3905 4372);
PAINT GREEN (-3905 4372);
DISPLAY INVISIBLE (-3905 4372);
FORCEADD INTEL_CORP_BPAGE..1
(-275 300);
FORCEPROP 1 LAST CDS_CON_LAST_MODIFIED Tue Dec 01 11:52:20 2015
J 0
(-1700 625);
PAINT GREEN (-1700 625);
DISPLAY INVISIBLE (-1700 625);
FORCEPROP 1 LAST CUSTOM_TXT_CDS <CURRENT_DESIGN_SHEET> OF <TOTAL_DESIGN_SHEETS>
J 0
(-775 325);
PAINT GREEN (-775 325);
FORCEPROP 1 LAST CUSTOM_TXT_CDS <CON_LAST_MODIFIED>
J 0
(-2200 650);
PAINT GREEN (-2200 650);
FORCEPROP 2 LAST CUSTOM_TXT_CDS <XR_PAGE_TITLE>
J 0
(-8165 5550);
DISPLAY 0.638298 (-8165 5550);
PAINT PINK (-8165 5550);
DISPLAY INVISIBLE (-8165 5550);
FORCEPROP 1 LAST SCH_TITLE POWER SWITCHES
J 0
(-8075 450);
DISPLAY 1.212766 (-8075 450);
PAINT ORANGE (-8075 450);
FORCEPROP 1 LAST SCH_ADDRESS1 2200 Mission College Blvd.
J 0
(-4250 425);
DISPLAY 0.617021 (-4250 425);
PAINT GREEN (-4250 425);
FORCEPROP 1 LAST SCH_ADDRESS2 P.O. BOX 58119
J 0
(-4250 375);
DISPLAY 0.617021 (-4250 375);
PAINT GREEN (-4250 375);
FORCEPROP 1 LAST SCH_ADDRESS3 Santa Clara, CA 95052-8119
J 0
(-4250 325);
DISPLAY 0.617021 (-4250 325);
PAINT GREEN (-4250 325);
FORCEPROP 1 LAST SCH_NUMBER H4694802
J 0
(-1575 450);
DISPLAY 1.212766 (-1575 450);
PAINT YELLOW (-1575 450);
FORCEPROP 1 LAST SCH_DEPT BESD
J 1
(-4725 400);
DISPLAY 1.212766 (-4725 400);
PAINT YELLOW (-4725 400);
FORCEPROP 1 LAST SCH_REV 2.420
J 0
(-525 450);
DISPLAY 0.978723 (-525 450);
PAINT YELLOW (-525 450);
FORCEPROP 2 LAST PAGE_BORDER TRUE
J 0
(-8165 5550);
DISPLAY 0.851064 (-8165 5550);
PAINT PINK (-8165 5550);
DISPLAY INVISIBLE (-8165 5550);
FORCEPROP 1 LAST COMMENT_BODY TRUE
J 0
(-263 312);
DISPLAY 0.468085 (-263 312);
PAINT GREEN (-263 312);
DISPLAY INVISIBLE (-263 312);
FORCEPROP 2 LAST CDS_LIB mstr_symbols
J 0
(-275 300);
PAINT ORANGE (-275 300);
DISPLAY INVISIBLE (-275 300);
FORCEPROP 2 LAST CDS_XR_PAGE_TITLE CR-198 : @BASEBOARD_FAB2_LIB.BASEBOARD_FAB2(SCH_1):PAGE198
J 0
(-8165 5550);
DISPLAY 0.638298 (-8165 5550);
PAINT PINK (-8165 5550);
DISPLAY INVISIBLE (-8165 5550);
FORCEADD DNS..2
(-6920 3045);
PAINT RED (-6920 3045);
FORCEPROP 1 LAST COMMENT_BODY TRUE
R 1
J 0
(-6845 2820);
DISPLAY 0.872340 (-6845 2820);
PAINT GREEN (-6845 2820);
DISPLAY INVISIBLE (-6845 2820);
FORCEPROP 2 LAST CDS_LIB mstr_misc
J 0
(-6920 3045);
PAINT ORANGE (-6920 3045);
DISPLAY INVISIBLE (-6920 3045);
WIRE 16 -1 (-3000 3650)(-2775 3650);
WIRE 16 -1 (-2775 3650)(-2775 3600);
WIRE 16 -1 (-3000 3600)(-2775 3600);
WIRE 16 -1 (-2775 3600)(-2775 3475);
WIRE 16 -1 (-7150 1800)(-7025 1800);
WIRE 16 -1 (-7150 2000)(-7150 1800);
WIRE 16 -1 (-7025 2000)(-7150 2000);
WIRE 16 -1 (-7375 2000)(-7150 2000);
WIRE 16 -1 (-7375 2000)(-7375 2350);
WIRE 16 -1 (-7725 2350)(-7375 2350);
WIRE 16 -1 (-7375 2350)(-7375 2475);
WIRE 16 -1 (-7725 2275)(-7725 2350);
WIRE 16 -1 (-6425 1700)(-6200 1700);
WIRE 16 -1 (-6200 1700)(-6200 1650);
WIRE 16 -1 (-6425 1650)(-6200 1650);
WIRE 16 -1 (-6200 1650)(-6200 1525);
WIRE 16 -1 (-7300 3775)(-7475 3775);
WIRE 16 -1 (-7475 3975)(-7475 3775);
WIRE 16 -1 (-7300 3975)(-7475 3975);
WIRE 16 -1 (-7475 3975)(-7650 3975);
WIRE 16 -1 (-7650 3975)(-7650 4350);
WIRE 16 -1 (-8000 4350)(-7650 4350);
WIRE 16 -1 (-7650 4350)(-7650 4475);
WIRE 16 -1 (-8000 4300)(-8000 4350);
WIRE 16 -1 (-3000 3850)(-1850 3850);
WIRE 16 -1 (-1850 3850)(-1850 4225);
WIRE 16 -1 (-1850 4225)(-1600 4225);
WIRE 16 -1 (-1600 4225)(-1600 4600);
WIRE 16 -1 (-1600 4225)(-1600 4050);
WIRE 16 -1 (-1375 4600)(-1600 4600);
WIRE 16 -1 (-1600 4600)(-1600 4675);
WIRE 16 -1 (-1050 4600)(-1375 4600);
WIRE 16 -1 (-1375 4500)(-1375 4600);
WIRE 16 -1 (-1050 4500)(-1050 4600);
WIRE 16 -1 (-3000 3750)(-1850 3750);
WIRE 16 -1 (-1850 3750)(-1850 3400);
WIRE 16 -1 (-1850 3400)(-1600 3400);
WIRE 16 -1 (-1600 3650)(-1600 3400);
WIRE 16 -1 (-1600 3400)(-1100 3400);
WIRE 16 -1 (-1100 3350)(-1100 3400);
WIRE 16 -1 (-1100 3450)(-1100 3400);
WIRE 16 -1 (-775 3450)(-1100 3450);
WIRE 16 -1 (-1100 3550)(-1100 3450);
WIRE 16 -1 (-775 3350)(-775 3450);
WIRE 16 -1 (-6425 1800)(-5650 1800);
WIRE 16 -1 (-5650 1800)(-5650 1450);
WIRE 16 -1 (-5650 1450)(-5325 1450);
WIRE 16 -1 (-5325 1650)(-5325 1450);
WIRE 16 -1 (-5325 1450)(-5125 1450);
WIRE 16 -1 (-5125 1350)(-5125 1450);
WIRE 16 -1 (-5125 1450)(-4675 1450);
WIRE 16 -1 (-4675 1300)(-4675 1450);
WIRE 16 -1 (-4675 1575)(-4675 1450);
WIRE 16 -1 (-6425 1900)(-5650 1900);
WIRE 16 -1 (-5650 1900)(-5650 2275);
WIRE 16 -1 (-5650 2275)(-5325 2275);
WIRE 16 -1 (-5325 2275)(-5325 2450);
WIRE 16 -1 (-5325 2275)(-5325 2050);
WIRE 16 -1 (-5100 2450)(-5325 2450);
WIRE 16 -1 (-5325 2450)(-5325 2525);
WIRE 16 -1 (-4775 2450)(-5100 2450);
WIRE 16 -1 (-5100 2350)(-5100 2450);
WIRE 16 -1 (-4775 2350)(-4775 2450);
WIRE 16 -1 (-8000 4050)(-8000 4100);
WIRE 16 -1 (-4300 4000)(-4300 4025);
WIRE 16 -1 (-7725 2050)(-7725 2075);
WIRE 16 -1 (-6700 3675)(-6475 3675);
WIRE 16 -1 (-6475 3675)(-6475 3625);
WIRE 16 -1 (-6700 3625)(-6475 3625);
WIRE 16 -1 (-6475 3625)(-6475 3500);
WIRE 16 -1 (-1050 4300)(-1050 4175);
WIRE 16 -1 (-1050 4175)(-1200 4175);
WIRE 16 -1 (-1200 4175)(-1375 4175);
WIRE 16 -1 (-1200 4125)(-1200 4175);
WIRE 16 -1 (-1375 4175)(-1375 4300);
WIRE 16 -1 (-775 3150)(-775 3025);
WIRE 16 -1 (-775 3025)(-925 3025);
WIRE 16 -1 (-925 3025)(-1100 3025);
WIRE 16 -1 (-925 2950)(-925 3025);
WIRE 16 -1 (-1100 3150)(-1100 3025);
WIRE 16 -1 (-5375 4050)(-5375 4175);
WIRE 16 -1 (-5075 4050)(-5375 4050);
WIRE 16 -1 (-5050 4050)(-5075 4050);
WIRE 16 -1 (-5075 3975)(-5075 4050);
WIRE 16 -1 (-5050 4175)(-5050 4050);
WIRE 16 -1 (-5000 3000)(-5000 3100);
WIRE 16 -1 (-4775 3000)(-5000 3000);
WIRE 16 -1 (-4675 3000)(-4775 3000);
WIRE 16 -1 (-4775 2900)(-4775 3000);
WIRE 16 -1 (-4675 3100)(-4675 3000);
WIRE 16 -1 (-4675 1100)(-4675 1025);
WIRE 16 -1 (-4675 1025)(-5125 1025);
WIRE 16 -1 (-5125 1025)(-5125 1150);
WIRE 16 -1 (-5125 975)(-5125 1025);
WIRE 16 -1 (-5100 2025)(-5100 2150);
WIRE 16 -1 (-4800 2025)(-5100 2025);
WIRE 16 -1 (-4775 2025)(-4800 2025);
WIRE 16 -1 (-4800 1950)(-4800 2025);
WIRE 16 -1 (-4775 2150)(-4775 2025);
WIRE 16 -1 (-6700 3875)(-5950 3875);
WIRE 16 -1 (-5950 3875)(-5950 4250);
WIRE 16 -1 (-5950 4250)(-5650 4250);
WIRE 16 -1 (-5650 4250)(-5600 4250);
WIRE 16 -1 (-5650 4250)(-5650 4100);
WIRE 16 -1 (-5600 4250)(-5600 4475);
WIRE 16 -1 (-5375 4475)(-5600 4475);
WIRE 16 -1 (-5600 4475)(-5600 4550);
WIRE 16 -1 (-5050 4475)(-5375 4475);
WIRE 16 -1 (-5375 4375)(-5375 4475);
WIRE 16 -1 (-5050 4375)(-5050 4475);
WIRE 16 -1 (-725 1125)(-725 1000);
WIRE 16 -1 (-725 1000)(-1175 1000);
WIRE 16 -1 (-1175 1000)(-1175 1125);
WIRE 16 -1 (-1175 950)(-1175 1000);
WIRE 16 -1 (-3775 2000)(-3775 2050);
WIRE 16 -1 (-3200 1975)(-3200 1775);
WIRE 16 -1 (-3075 1975)(-3200 1975);
WIRE 16 -1 (-3425 1975)(-3200 1975);
WIRE 16 -1 (-3200 1775)(-3075 1775);
WIRE 16 -1 (-3425 1975)(-3425 2325);
WIRE 16 -1 (-3775 2325)(-3425 2325);
WIRE 16 -1 (-3425 2325)(-3425 2450);
WIRE 16 -1 (-3775 2250)(-3775 2325);
WIRE 16 -1 (-6700 3775)(-5950 3775);
WIRE 16 -1 (-5950 3775)(-5950 3425);
WIRE 16 -1 (-5950 3425)(-5650 3425);
WIRE 16 -1 (-5650 3700)(-5650 3425);
WIRE 16 -1 (-5650 3425)(-5125 3425);
WIRE 16 -1 (-5125 3425)(-5000 3425);
WIRE 16 -1 (-5125 3625)(-5125 3425);
WIRE 16 -1 (-4675 3425)(-5000 3425);
WIRE 16 -1 (-5000 3300)(-5000 3425);
WIRE 16 -1 (-4675 3300)(-4675 3425);
WIRE 16 -1 (-2475 1675)(-2250 1675);
WIRE 16 -1 (-2250 1675)(-2250 1625);
WIRE 16 -1 (-2475 1625)(-2250 1625);
WIRE 16 -1 (-2250 1625)(-2250 1500);
WIRE 16 -1 (-2475 1875)(-1700 1875);
WIRE 16 -1 (-1700 1875)(-1700 2250);
WIRE 16 -1 (-1700 2250)(-1375 2250);
WIRE 16 -1 (-1375 2250)(-1375 2425);
WIRE 16 -1 (-1375 2250)(-1375 2050);
WIRE 16 -1 (-1150 2425)(-1375 2425);
WIRE 16 -1 (-1375 2425)(-1375 2500);
WIRE 16 -1 (-825 2425)(-1150 2425);
WIRE 16 -1 (-1150 2325)(-1150 2425);
WIRE 16 -1 (-825 2325)(-825 2425);
WIRE 16 -1 (-825 2125)(-825 2000);
WIRE 16 -1 (-850 2000)(-825 2000);
WIRE 16 -1 (-1150 2000)(-850 2000);
WIRE 16 -1 (-850 1950)(-850 2000);
WIRE 16 -1 (-1150 2000)(-1150 2125);
WIRE 16 -1 (-2475 1775)(-1700 1775);
WIRE 16 -1 (-1700 1775)(-1700 1425);
WIRE 16 -1 (-1700 1425)(-1375 1425);
WIRE 16 -1 (-1375 1650)(-1375 1425);
WIRE 16 -1 (-1375 1425)(-1175 1425);
WIRE 16 -1 (-1175 1325)(-1175 1425);
WIRE 16 -1 (-1175 1425)(-725 1425);
WIRE 16 -1 (-725 1550)(-725 1425);
WIRE 16 -1 (-725 1425)(-725 1325);
WIRE 16 -1 (-6925 3150)(-6925 3225);
WIRE 16 -1 (-6850 2475)(-6850 2525);
WIRE 16 -1 (-3600 3750)(-3775 3750);
WIRE 16 -1 (-3775 3750)(-3775 3950);
WIRE 16 -1 (-3600 3950)(-3775 3950);
WIRE 16 -1 (-3775 3950)(-3950 3950);
WIRE 16 -1 (-3950 3950)(-3950 4250);
WIRE 16 -1 (-4300 4250)(-3950 4250);
WIRE 16 -1 (-3950 4250)(-3950 4300);
WIRE 16 -1 (-4300 4225)(-4300 4250);
WIRE 16 -1 (-6425 2000)(-6300 2000);
FORCEPROP 2 LAST SIG_NAME TP_SLG55021_P12V_MAIN_8
J 0
(-6360 2010);
DISPLAY 0.617021 (-6360 2010);
PAINT ORANGE (-6360 2010);
FORCEPROP 2 LASTPROP $XRERR UNIQUE?
J 0
(-6270 2000);
DISPLAY 0.638298 (-6270 2000);
PAINT MONO (-6270 2000);
DISPLAY INVISIBLE (-6270 2000);
WIRE 16 -1 (-6425 1850)(-5550 1850);
FORCEPROP 0 LAST VOLTAGE +3.3V
J 0
(-6275 1925);
DISPLAY 1.021277 (-6275 1925);
PAINT SKYBLUE (-6275 1925);
DISPLAY INVISIBLE (-6275 1925);
FORCEPROP 0 LAST SIG_NAME P12V_SWITCH_G
J 0
(-6210 1860);
DISPLAY 0.617021 (-6210 1860);
PAINT ORANGE (-6210 1860);
FORCEPROP 2 LASTPROP $XRERR UNIQUE?
J 0
(-6450 1860);
DISPLAY 0.638298 (-6450 1860);
PAINT MONO (-6450 1860);
DISPLAY INVISIBLE (-6450 1860);
WIRE 16 -1 (-5550 1850)(-5550 1950);
WIRE 16 -1 (-5550 1950)(-5525 1950);
WIRE 16 -1 (-7025 1900)(-7875 1900);
FORCEPROP 0 LAST SIG_NAME FM_P12V_MAIN_SW_EN
J 0
(-7844 1926);
DISPLAY 0.617021 (-7844 1926);
PAINT ORANGE (-7844 1926);
WIRE 16 -1 (-3600 3850)(-4300 3850);
WIRE 16 -1 (-4300 2800)(-4300 3850);
WIRE 16 -1 (-4300 2800)(-6850 2800);
WIRE 16 -1 (-6850 2725)(-6850 2800);
WIRE 16 -1 (-6850 2800)(-6925 2800);
WIRE 16 -1 (-6925 2950)(-6925 2800);
WIRE 16 -1 (-7600 2800)(-6925 2800);
FORCEPROP 0 LAST SIG_NAME FM_CTNR_PS_ON
J 0
(-7560 2810);
DISPLAY 0.617021 (-7560 2810);
PAINT ORANGE (-7560 2810);
WIRE 16 -1 (-3000 3950)(-2500 3950);
FORCEPROP 0 LAST SIG_NAME TP_SLG55021_P5V_8
J 0
(-2935 3960);
DISPLAY 0.617021 (-2935 3960);
PAINT ORANGE (-2935 3960);
FORCEPROP 2 LASTPROP $XRERR UNIQUE?
J 0
(-2470 3950);
DISPLAY 0.638298 (-2470 3950);
PAINT MONO (-2470 3950);
DISPLAY INVISIBLE (-2470 3950);
WIRE 16 -1 (-3000 3800)(-1825 3800);
FORCEPROP 0 LAST VOLTAGE +5V
J 0
(-2850 3875);
DISPLAY 1.021277 (-2850 3875);
PAINT SKYBLUE (-2850 3875);
DISPLAY INVISIBLE (-2850 3875);
FORCEPROP 0 LAST SIG_NAME P5V_SWITCH_G
J 0
(-2860 3810);
DISPLAY 0.617021 (-2860 3810);
PAINT ORANGE (-2860 3810);
FORCEPROP 2 LASTPROP $XRERR UNIQUE?
J 0
(-3100 3810);
DISPLAY 0.638298 (-3100 3810);
PAINT MONO (-3100 3810);
DISPLAY INVISIBLE (-3100 3810);
WIRE 16 -1 (-1825 3800)(-1825 3950);
WIRE 16 -1 (-1825 3950)(-1800 3950);
WIRE 16 -1 (-1625 1950)(-1575 1950);
WIRE 16 -1 (-1625 1825)(-1625 1950);
WIRE 16 -1 (-1625 1825)(-2475 1825);
FORCEPROP 0 LAST VOLTAGE +5V
J 0
(-2325 1900);
DISPLAY 1.021277 (-2325 1900);
PAINT SKYBLUE (-2325 1900);
DISPLAY INVISIBLE (-2325 1900);
FORCEPROP 0 LAST SIG_NAME P12V_FAN_SWITCH_G
J 0
(-2335 1835);
DISPLAY 0.617021 (-2335 1835);
PAINT ORANGE (-2335 1835);
FORCEPROP 2 LASTPROP $XRERR UNIQUE?
J 0
(-2575 1835);
DISPLAY 0.638298 (-2575 1835);
PAINT MONO (-2575 1835);
DISPLAY INVISIBLE (-2575 1835);
WIRE 16 -1 (-2475 1975)(-1975 1975);
FORCEPROP 0 LAST SIG_NAME TP_SLG55021_P12V_FAN_8
J 0
(-2410 1985);
DISPLAY 0.617021 (-2410 1985);
PAINT ORANGE (-2410 1985);
FORCEPROP 2 LASTPROP $XRERR UNIQUE?
J 0
(-1945 1975);
DISPLAY 0.638298 (-1945 1975);
PAINT MONO (-1945 1975);
DISPLAY INVISIBLE (-1945 1975);
WIRE 16 -1 (-3075 1875)(-3925 1875);
FORCEPROP 0 LAST SIG_NAME FM_ENABLE_FAN_POWER
J 0
(-3885 1885);
DISPLAY 0.617021 (-3885 1885);
PAINT ORANGE (-3885 1885);
WIRE 16 -1 (-5900 4000)(-5850 4000);
WIRE 16 -1 (-5900 3825)(-5900 4000);
WIRE 16 -1 (-6700 3825)(-5900 3825);
FORCEPROP 0 LAST VOLTAGE 3.3
J 0
(-6550 3900);
DISPLAY 1.021277 (-6550 3900);
PAINT SKYBLUE (-6550 3900);
DISPLAY INVISIBLE (-6550 3900);
FORCEPROP 0 LAST SIG_NAME P3V3_SWITCH_G
J 0
(-6560 3835);
DISPLAY 0.617021 (-6560 3835);
PAINT ORANGE (-6560 3835);
FORCEPROP 2 LASTPROP $XRERR UNIQUE?
J 0
(-6800 3835);
DISPLAY 0.638298 (-6800 3835);
PAINT MONO (-6800 3835);
DISPLAY INVISIBLE (-6800 3835);
WIRE 16 -1 (-6700 3975)(-6250 3975);
FORCEPROP 0 LAST SIG_NAME TP_SLG55021_P3V3_8
J 0
(-6635 3985);
DISPLAY 0.617021 (-6635 3985);
PAINT ORANGE (-6635 3985);
FORCEPROP 2 LASTPROP $XRERR UNIQUE?
J 0
(-6220 3975);
DISPLAY 0.638298 (-6220 3975);
PAINT MONO (-6220 3975);
DISPLAY INVISIBLE (-6220 3975);
WIRE 16 -1 (-7300 3875)(-7875 3875);
FORCEPROP 0 LAST SIG_NAME FM_P3V3_CPLD_EN
J 0
(-7860 3885);
DISPLAY 0.617021 (-7860 3885);
PAINT ORANGE (-7860 3885);
DOT 1 (-850 2000);
DOT 1 (-3425 2325);
DOT 1 (-5100 2450);
DOT 1 (-1150 2425);
DOT 1 (-1200 4175);
DOT 1 (-1375 4600);
DOT 1 (-1600 4600);
DOT 1 (-1600 4225);
DOT 1 (-3950 4250);
DOT 1 (-925 3025);
DOT 1 (-1100 3450);
DOT 1 (-1100 3400);
DOT 1 (-1600 3400);
DOT 1 (-1375 2425);
DOT 1 (-1375 2250);
DOT 1 (-725 1425);
DOT 1 (-1175 1425);
DOT 1 (-1375 1425);
DOT 1 (-1175 1000);
DOT 1 (-2775 3600);
DOT 1 (-3775 3950);
DOT 1 (-2250 1625);
DOT 1 (-3200 1975);
DOT 1 (-5375 4475);
DOT 1 (-5600 4475);
DOT 1 (-5650 4250);
DOT 1 (-7650 4350);
DOT 1 (-5075 4050);
DOT 1 (-5000 3425);
DOT 1 (-4775 3000);
DOT 1 (-5125 3425);
DOT 1 (-5650 3425);
DOT 1 (-5325 2450);
DOT 1 (-5325 2275);
DOT 1 (-4800 2025);
DOT 1 (-4675 1450);
DOT 1 (-5325 1450);
DOT 1 (-5125 1450);
DOT 1 (-5125 1025);
DOT 1 (-6475 3625);
DOT 1 (-6850 2800);
DOT 1 (-6925 2800);
DOT 1 (-7475 3975);
DOT 1 (-7375 2350);
DOT 1 (-6200 1650);
DOT 1 (-7150 2000);
FORCENOTE
ROOM=P5V_PWR_SWITCH
(-3625 3250) 0;
DISPLAY LEFT (-3625 3250);
DISPLAY 1.021277 (-3625 3250);
PAINT PURPLE (-3625 3250);
FORCENOTE
ROOM=P12V_FAN_PWR_SWITCH
(-3225 1225) 0;
DISPLAY LEFT (-3225 1225);
DISPLAY 1.021277 (-3225 1225);
PAINT PURPLE (-3225 1225);
FORCENOTE
ROOM=P3V3_PWR_SWITCH
(-7625 3450) 0;
DISPLAY LEFT (-7625 3450);
DISPLAY 1.021277 (-7625 3450);
PAINT PURPLE (-7625 3450);
FORCENOTE
ROOM=P12V_PWR_SWITCH
(-7175 1250) 0;
DISPLAY LEFT (-7175 1250);
DISPLAY 1.021277 (-7175 1250);
PAINT PURPLE (-7175 1250);
FORCENOTE
BOM_COST=PWR_SWITCH
(-8100 600) 0;
DISPLAY LEFT (-8100 600);
DISPLAY 1.021277 (-8100 600);
PAINT PURPLE (-8100 600);
QUIT
